FILE_TYPE = MACRO_DRAWING;
SET COLOR_WIRE YELLOW;
SET COLOR_PROP ORANGE;
SET COLOR_DOT WHITE;
SET COLOR_ARC YELLOW;
SET COLOR_BODY GREEN;
SET COLOR_NOTE PURPLE;
SET PROP_DISPLAY VALUE;
SET PAGE_NUMBER P85;
FORCEADD Q_RES..2
(-1950 250);
FORCEPROP 1 LAST PART_NUMBER CS33572FB01
J 0
(-1910 125);
DISPLAY 0.978723 (-1910 125);
DISPLAY INVISIBLE (-1910 125);
FORCEPROP 1 LAST VALUE 35.7K
J 0
(-1905 325);
DISPLAY 0.978723 (-1905 325);
FORCEPROP 1 LAST TOLERANCE 1%
J 0
(-1905 275);
DISPLAY 0.978723 (-1905 275);
FORCEPROP 1 LAST PACK_TYPE 0402LF
J 0
(-1910 75);
DISPLAY 0.978723 (-1910 75);
FORCEPROP 1 LAST WATTAGE 1/16W
J 0
(-1910 225);
DISPLAY 0.978723 (-1910 225);
FORCEPROP 1 LAST MATERIAL CHIP
J 0
(-1910 175);
DISPLAY 0.978723 (-1910 175);
FORCEPROP 1 LAST $LOCATION R29
J 0
(-1905 375);
DISPLAY 0.978723 (-1905 375);
FORCEPROP 1 LASTPIN (-1950 350) $PN 1
J 0
(-1945 312);
DISPLAY 0.787234 (-1945 312);
FORCEPROP 1 LASTPIN (-1950 150) $PN 2
J 0
(-1945 160);
DISPLAY 0.787234 (-1945 160);
FORCEPROP 2 LAST CDS_LIB pure_quanta
J 0
(-1950 250);
PAINT MONO (-1950 250);
DISPLAY INVISIBLE (-1950 250);
FORCEPROP 2 LAST CDS_LOCATION R29
J 0
(-1900 475);
DISPLAY 1.021277 (-1900 475);
DISPLAY INVISIBLE (-1900 475);
FORCEPROP 2 LAST $SEC 1
J 0
(-1900 475);
DISPLAY 0.680851 (-1900 475);
PAINT MONO (-1900 475);
DISPLAY INVISIBLE (-1900 475);
FORCEPROP 2 LAST CDS_SEC 1
J 0
(-1900 475);
DISPLAY 1.021277 (-1900 475);
DISPLAY INVISIBLE (-1900 475);
FORCEPROP 1 LAST PATH I1
J 0
(-1900 425);
DISPLAY 0.978723 (-1900 425);
PAINT WHITE (-1900 425);
DISPLAY INVISIBLE (-1900 425);
FORCEADD OFFPAGE..1
(-3100 2150);
FORCEPROP 2 LAST $XR3 84 
J 0
(-3352 2114);
DISPLAY 0.638298 (-3352 2114);
PAINT MONO (-3352 2114);
FORCEPROP 2 LAST $XR2 83 
J 0
(-3532 2150);
DISPLAY 0.638298 (-3532 2150);
PAINT MONO (-3532 2150);
FORCEPROP 2 LAST $XR1 82 
J 0
(-3442 2150);
DISPLAY 0.638298 (-3442 2150);
PAINT MONO (-3442 2150);
FORCEPROP 2 LAST $XR0 129 
J 0
(-3352 2150);
DISPLAY 0.638298 (-3352 2150);
PAINT MONO (-3352 2150);
FORCEPROP 2 LAST CDS_LIB standard
J 0
(-3100 2150);
PAINT MONO (-3100 2150);
DISPLAY INVISIBLE (-3100 2150);
FORCEPROP 1 LAST OFFPAGE TRUE
J 0
(-2775 2025);
DISPLAY 0.872340 (-2775 2025);
DISPLAY INVISIBLE (-2775 2025);
FORCEPROP 1 LAST COMMENT_BODY TRUE
J 0
(-2975 2050);
DISPLAY 0.872340 (-2975 2050);
PAINT GREEN (-2975 2050);
DISPLAY INVISIBLE (-2975 2050);
FORCEPROP 2 LAST PATH I10
J 0
(-3050 2225);
DISPLAY 1.021277 (-3050 2225);
DISPLAY INVISIBLE (-3050 2225);
FORCEADD TAP..1
(-525 3750);
FORCEPROP 3 LASTPIN (-575 3750) SIG_NAME M_B_CPU0_SA_DQ<18>
J 0
(-565 3760);
DISPLAY 0.659574 (-565 3760);
PAINT MONO (-565 3760);
DISPLAY INVISIBLE (-565 3760);
FORCEPROP 1 LASTPIN (-575 3750) BN 18
J 0
(-587 3758);
DISPLAY 0.680851 (-587 3758);
PAINT GREEN (-587 3758);
FORCEPROP 2 LAST CDS_LIB standard
J 0
(-525 3750);
PAINT MONO (-525 3750);
DISPLAY INVISIBLE (-525 3750);
FORCEPROP 1 LAST BODY_TYPE PLUMBING
J 0
(-525 3800);
DISPLAY 0.872340 (-525 3800);
PAINT GREEN (-525 3800);
DISPLAY INVISIBLE (-525 3800);
FORCEPROP 1 LAST HDL_TAP TRUE
J 0
(-200 3625);
DISPLAY 0.872340 (-200 3625);
DISPLAY INVISIBLE (-200 3625);
FORCEPROP 1 LAST PATH I100
J 0
(-527 3750);
DISPLAY 0.872340 (-527 3750);
PAINT GREEN (-527 3750);
DISPLAY INVISIBLE (-527 3750);
FORCEADD TAP..1
(-525 3700);
FORCEPROP 3 LASTPIN (-575 3700) SIG_NAME M_B_CPU0_SA_DQ<17>
J 0
(-565 3710);
DISPLAY 0.659574 (-565 3710);
PAINT MONO (-565 3710);
DISPLAY INVISIBLE (-565 3710);
FORCEPROP 1 LASTPIN (-575 3700) BN 17
J 0
(-587 3708);
DISPLAY 0.680851 (-587 3708);
PAINT GREEN (-587 3708);
FORCEPROP 2 LAST CDS_LIB standard
J 0
(-525 3700);
PAINT MONO (-525 3700);
DISPLAY INVISIBLE (-525 3700);
FORCEPROP 1 LAST BODY_TYPE PLUMBING
J 0
(-525 3750);
DISPLAY 0.872340 (-525 3750);
PAINT GREEN (-525 3750);
DISPLAY INVISIBLE (-525 3750);
FORCEPROP 1 LAST HDL_TAP TRUE
J 0
(-200 3575);
DISPLAY 0.872340 (-200 3575);
DISPLAY INVISIBLE (-200 3575);
FORCEPROP 1 LAST PATH I101
J 0
(-527 3700);
DISPLAY 0.872340 (-527 3700);
PAINT GREEN (-527 3700);
DISPLAY INVISIBLE (-527 3700);
FORCEADD TAP..1
(-525 3800);
FORCEPROP 3 LASTPIN (-575 3800) SIG_NAME M_B_CPU0_SA_DQ<19>
J 0
(-565 3810);
DISPLAY 0.659574 (-565 3810);
PAINT MONO (-565 3810);
DISPLAY INVISIBLE (-565 3810);
FORCEPROP 1 LASTPIN (-575 3800) BN 19
J 0
(-587 3808);
DISPLAY 0.680851 (-587 3808);
PAINT GREEN (-587 3808);
FORCEPROP 2 LAST CDS_LIB standard
J 0
(-525 3800);
PAINT MONO (-525 3800);
DISPLAY INVISIBLE (-525 3800);
FORCEPROP 1 LAST BODY_TYPE PLUMBING
J 0
(-525 3850);
DISPLAY 0.872340 (-525 3850);
PAINT GREEN (-525 3850);
DISPLAY INVISIBLE (-525 3850);
FORCEPROP 1 LAST HDL_TAP TRUE
J 0
(-200 3675);
DISPLAY 0.872340 (-200 3675);
DISPLAY INVISIBLE (-200 3675);
FORCEPROP 1 LAST PATH I102
J 0
(-527 3800);
DISPLAY 0.872340 (-527 3800);
PAINT GREEN (-527 3800);
DISPLAY INVISIBLE (-527 3800);
FORCEADD TAP..1
(-525 3850);
FORCEPROP 3 LASTPIN (-575 3850) SIG_NAME M_B_CPU0_SA_DQ<20>
J 0
(-565 3860);
DISPLAY 0.659574 (-565 3860);
PAINT MONO (-565 3860);
DISPLAY INVISIBLE (-565 3860);
FORCEPROP 1 LASTPIN (-575 3850) BN 20
J 0
(-587 3858);
DISPLAY 0.680851 (-587 3858);
PAINT GREEN (-587 3858);
FORCEPROP 2 LAST CDS_LIB standard
J 0
(-525 3850);
PAINT MONO (-525 3850);
DISPLAY INVISIBLE (-525 3850);
FORCEPROP 1 LAST BODY_TYPE PLUMBING
J 0
(-525 3900);
DISPLAY 0.872340 (-525 3900);
PAINT GREEN (-525 3900);
DISPLAY INVISIBLE (-525 3900);
FORCEPROP 1 LAST HDL_TAP TRUE
J 0
(-200 3725);
DISPLAY 0.872340 (-200 3725);
DISPLAY INVISIBLE (-200 3725);
FORCEPROP 1 LAST PATH I103
J 0
(-527 3850);
DISPLAY 0.872340 (-527 3850);
PAINT GREEN (-527 3850);
DISPLAY INVISIBLE (-527 3850);
FORCEADD TAP..1
(-525 3900);
FORCEPROP 3 LASTPIN (-575 3900) SIG_NAME M_B_CPU0_SA_DQ<21>
J 0
(-565 3910);
DISPLAY 0.659574 (-565 3910);
PAINT MONO (-565 3910);
DISPLAY INVISIBLE (-565 3910);
FORCEPROP 1 LASTPIN (-575 3900) BN 21
J 0
(-587 3908);
DISPLAY 0.680851 (-587 3908);
PAINT GREEN (-587 3908);
FORCEPROP 2 LAST CDS_LIB standard
J 0
(-525 3900);
PAINT MONO (-525 3900);
DISPLAY INVISIBLE (-525 3900);
FORCEPROP 1 LAST BODY_TYPE PLUMBING
J 0
(-525 3950);
DISPLAY 0.872340 (-525 3950);
PAINT GREEN (-525 3950);
DISPLAY INVISIBLE (-525 3950);
FORCEPROP 1 LAST HDL_TAP TRUE
J 0
(-200 3775);
DISPLAY 0.872340 (-200 3775);
DISPLAY INVISIBLE (-200 3775);
FORCEPROP 1 LAST PATH I104
J 0
(-527 3900);
DISPLAY 0.872340 (-527 3900);
PAINT GREEN (-527 3900);
DISPLAY INVISIBLE (-527 3900);
FORCEADD TAP..1
(-525 3950);
FORCEPROP 3 LASTPIN (-575 3950) SIG_NAME M_B_CPU0_SA_DQ<22>
J 0
(-565 3960);
DISPLAY 0.659574 (-565 3960);
PAINT MONO (-565 3960);
DISPLAY INVISIBLE (-565 3960);
FORCEPROP 1 LASTPIN (-575 3950) BN 22
J 0
(-587 3958);
DISPLAY 0.680851 (-587 3958);
PAINT GREEN (-587 3958);
FORCEPROP 2 LAST CDS_LIB standard
J 0
(-525 3950);
DISPLAY INVISIBLE (-525 3950);
FORCEPROP 1 LAST BODY_TYPE PLUMBING
J 0
(-525 4000);
DISPLAY 0.872340 (-525 4000);
PAINT GREEN (-525 4000);
DISPLAY INVISIBLE (-525 4000);
FORCEPROP 1 LAST HDL_TAP TRUE
J 0
(-200 3825);
DISPLAY 0.872340 (-200 3825);
DISPLAY INVISIBLE (-200 3825);
FORCEPROP 1 LAST PATH I105
J 0
(-527 3950);
DISPLAY 0.872340 (-527 3950);
PAINT GREEN (-527 3950);
DISPLAY INVISIBLE (-527 3950);
FORCEADD TAP..1
(-525 4000);
FORCEPROP 3 LASTPIN (-575 4000) SIG_NAME M_B_CPU0_SA_DQ<23>
J 0
(-565 4010);
DISPLAY 0.659574 (-565 4010);
PAINT MONO (-565 4010);
DISPLAY INVISIBLE (-565 4010);
FORCEPROP 1 LASTPIN (-575 4000) BN 23
J 0
(-587 4008);
DISPLAY 0.680851 (-587 4008);
PAINT GREEN (-587 4008);
FORCEPROP 2 LAST CDS_LIB standard
J 0
(-525 4000);
DISPLAY INVISIBLE (-525 4000);
FORCEPROP 1 LAST BODY_TYPE PLUMBING
J 0
(-525 4050);
DISPLAY 0.872340 (-525 4050);
PAINT GREEN (-525 4050);
DISPLAY INVISIBLE (-525 4050);
FORCEPROP 1 LAST HDL_TAP TRUE
J 0
(-200 3875);
DISPLAY 0.872340 (-200 3875);
DISPLAY INVISIBLE (-200 3875);
FORCEPROP 1 LAST PATH I106
J 0
(-527 4000);
DISPLAY 0.872340 (-527 4000);
PAINT GREEN (-527 4000);
DISPLAY INVISIBLE (-527 4000);
FORCEADD TAP..1
(-525 4050);
FORCEPROP 3 LASTPIN (-575 4050) SIG_NAME M_B_CPU0_SA_DQ<24>
J 0
(-565 4060);
DISPLAY 0.659574 (-565 4060);
PAINT MONO (-565 4060);
DISPLAY INVISIBLE (-565 4060);
FORCEPROP 1 LASTPIN (-575 4050) BN 24
J 0
(-587 4058);
DISPLAY 0.680851 (-587 4058);
PAINT GREEN (-587 4058);
FORCEPROP 2 LAST CDS_LIB standard
J 0
(-525 4050);
DISPLAY INVISIBLE (-525 4050);
FORCEPROP 1 LAST BODY_TYPE PLUMBING
J 0
(-525 4100);
DISPLAY 0.872340 (-525 4100);
PAINT GREEN (-525 4100);
DISPLAY INVISIBLE (-525 4100);
FORCEPROP 1 LAST HDL_TAP TRUE
J 0
(-200 3925);
DISPLAY 0.872340 (-200 3925);
DISPLAY INVISIBLE (-200 3925);
FORCEPROP 1 LAST PATH I107
J 0
(-527 4050);
DISPLAY 0.872340 (-527 4050);
PAINT GREEN (-527 4050);
DISPLAY INVISIBLE (-527 4050);
FORCEADD TAP..1
(-525 4100);
FORCEPROP 3 LASTPIN (-575 4100) SIG_NAME M_B_CPU0_SA_DQ<25>
J 0
(-565 4110);
DISPLAY 0.659574 (-565 4110);
PAINT MONO (-565 4110);
DISPLAY INVISIBLE (-565 4110);
FORCEPROP 1 LASTPIN (-575 4100) BN 25
J 0
(-587 4108);
DISPLAY 0.680851 (-587 4108);
PAINT GREEN (-587 4108);
FORCEPROP 2 LAST CDS_LIB standard
J 0
(-525 4100);
DISPLAY INVISIBLE (-525 4100);
FORCEPROP 1 LAST BODY_TYPE PLUMBING
J 0
(-525 4150);
DISPLAY 0.872340 (-525 4150);
PAINT GREEN (-525 4150);
DISPLAY INVISIBLE (-525 4150);
FORCEPROP 1 LAST HDL_TAP TRUE
J 0
(-200 3975);
DISPLAY 0.872340 (-200 3975);
DISPLAY INVISIBLE (-200 3975);
FORCEPROP 1 LAST PATH I108
J 0
(-527 4100);
DISPLAY 0.872340 (-527 4100);
PAINT GREEN (-527 4100);
DISPLAY INVISIBLE (-527 4100);
FORCEADD TAP..1
(-525 4150);
FORCEPROP 3 LASTPIN (-575 4150) SIG_NAME M_B_CPU0_SA_DQ<26>
J 0
(-565 4160);
DISPLAY 0.659574 (-565 4160);
PAINT MONO (-565 4160);
DISPLAY INVISIBLE (-565 4160);
FORCEPROP 1 LASTPIN (-575 4150) BN 26
J 0
(-587 4158);
DISPLAY 0.680851 (-587 4158);
PAINT GREEN (-587 4158);
FORCEPROP 2 LAST CDS_LIB standard
J 0
(-525 4150);
DISPLAY INVISIBLE (-525 4150);
FORCEPROP 1 LAST BODY_TYPE PLUMBING
J 0
(-525 4200);
DISPLAY 0.872340 (-525 4200);
PAINT GREEN (-525 4200);
DISPLAY INVISIBLE (-525 4200);
FORCEPROP 1 LAST HDL_TAP TRUE
J 0
(-200 4025);
DISPLAY 0.872340 (-200 4025);
DISPLAY INVISIBLE (-200 4025);
FORCEPROP 1 LAST PATH I109
J 0
(-527 4150);
DISPLAY 0.872340 (-527 4150);
PAINT GREEN (-527 4150);
DISPLAY INVISIBLE (-527 4150);
FORCEADD VCC_CORE..1
(-3000 2275);
FORCEPROP 3 LASTPIN (-3000 2225) SIG_NAME P3V3_AUX\g
J 0
(-2990 2235);
DISPLAY 0.659574 (-2990 2235);
PAINT MONO (-2990 2235);
DISPLAY INVISIBLE (-2990 2235);
FORCEPROP 1 LAST HDL_POWER P3V3_AUX
J 1
(-3000 2325);
DISPLAY 1.148936 (-3000 2325);
PAINT GREEN (-3000 2325);
FORCEPROP 2 LAST CDS_LIB logical_power
J 0
(-3000 2275);
PAINT MONO (-3000 2275);
DISPLAY INVISIBLE (-3000 2275);
FORCEPROP 1 LAST PATH I11
J 0
(-2950 2300);
DISPLAY 0.872340 (-2950 2300);
PAINT AQUA (-2950 2300);
DISPLAY INVISIBLE (-2950 2300);
FORCEADD TAP..1
(-525 4250);
FORCEPROP 3 LASTPIN (-575 4250) SIG_NAME M_B_CPU0_SA_DQ<28>
J 0
(-565 4260);
DISPLAY 0.659574 (-565 4260);
PAINT MONO (-565 4260);
DISPLAY INVISIBLE (-565 4260);
FORCEPROP 1 LASTPIN (-575 4250) BN 28
J 0
(-587 4258);
DISPLAY 0.680851 (-587 4258);
PAINT GREEN (-587 4258);
FORCEPROP 2 LAST CDS_LIB standard
J 0
(-525 4250);
DISPLAY INVISIBLE (-525 4250);
FORCEPROP 1 LAST BODY_TYPE PLUMBING
J 0
(-525 4300);
DISPLAY 0.872340 (-525 4300);
PAINT GREEN (-525 4300);
DISPLAY INVISIBLE (-525 4300);
FORCEPROP 1 LAST HDL_TAP TRUE
J 0
(-200 4125);
DISPLAY 0.872340 (-200 4125);
DISPLAY INVISIBLE (-200 4125);
FORCEPROP 1 LAST PATH I110
J 0
(-527 4250);
DISPLAY 0.872340 (-527 4250);
PAINT GREEN (-527 4250);
DISPLAY INVISIBLE (-527 4250);
FORCEADD TAP..1
(-525 4200);
FORCEPROP 3 LASTPIN (-575 4200) SIG_NAME M_B_CPU0_SA_DQ<27>
J 0
(-565 4210);
DISPLAY 0.659574 (-565 4210);
PAINT MONO (-565 4210);
DISPLAY INVISIBLE (-565 4210);
FORCEPROP 1 LASTPIN (-575 4200) BN 27
J 0
(-587 4208);
DISPLAY 0.680851 (-587 4208);
PAINT GREEN (-587 4208);
FORCEPROP 2 LAST CDS_LIB standard
J 0
(-525 4200);
DISPLAY INVISIBLE (-525 4200);
FORCEPROP 1 LAST BODY_TYPE PLUMBING
J 0
(-525 4250);
DISPLAY 0.872340 (-525 4250);
PAINT GREEN (-525 4250);
DISPLAY INVISIBLE (-525 4250);
FORCEPROP 1 LAST HDL_TAP TRUE
J 0
(-200 4075);
DISPLAY 0.872340 (-200 4075);
DISPLAY INVISIBLE (-200 4075);
FORCEPROP 1 LAST PATH I111
J 0
(-527 4200);
DISPLAY 0.872340 (-527 4200);
PAINT GREEN (-527 4200);
DISPLAY INVISIBLE (-527 4200);
FORCEADD OFFPAGE..1
(-3100 4425);
FORCEPROP 2 LAST $XR1 84 
J 0
(-3411 4425);
DISPLAY 0.638298 (-3411 4425);
PAINT MONO (-3411 4425);
FORCEPROP 2 LAST $XR0 21 
J 0
(-3321 4425);
DISPLAY 0.638298 (-3321 4425);
PAINT MONO (-3321 4425);
FORCEPROP 2 LAST CDS_LIB standard
J 0
(-3100 4425);
PAINT MONO (-3100 4425);
DISPLAY INVISIBLE (-3100 4425);
FORCEPROP 1 LAST OFFPAGE TRUE
J 0
(-2775 4300);
DISPLAY 0.872340 (-2775 4300);
DISPLAY INVISIBLE (-2775 4300);
FORCEPROP 1 LAST COMMENT_BODY TRUE
J 0
(-2975 4325);
DISPLAY 0.872340 (-2975 4325);
PAINT GREEN (-2975 4325);
DISPLAY INVISIBLE (-2975 4325);
FORCEPROP 2 LAST PATH I112
J 0
(-3050 4500);
DISPLAY 1.021277 (-3050 4500);
DISPLAY INVISIBLE (-3050 4500);
FORCEADD TAP..1
R 2
(-2175 4300);
FORCEPROP 3 LASTPIN (-2125 4300) SIG_NAME M_B_CPU0_SA_CA<4>
J 0
(-2115 4310);
DISPLAY 0.659574 (-2115 4310);
PAINT MONO (-2115 4310);
DISPLAY INVISIBLE (-2115 4310);
FORCEPROP 1 LASTPIN (-2125 4300) BN 4
J 2
(-2113 4308);
DISPLAY 0.680851 (-2113 4308);
PAINT GREEN (-2113 4308);
FORCEPROP 2 LAST CDS_LIB standard
J 0
(-2175 4300);
DISPLAY INVISIBLE (-2175 4300);
FORCEPROP 1 LAST BODY_TYPE PLUMBING
J 2
(-2175 4350);
DISPLAY 0.872340 (-2175 4350);
PAINT GREEN (-2175 4350);
DISPLAY INVISIBLE (-2175 4350);
FORCEPROP 1 LAST HDL_TAP TRUE
J 2
(-2500 4175);
DISPLAY 0.872340 (-2500 4175);
DISPLAY INVISIBLE (-2500 4175);
FORCEPROP 1 LAST PATH I113
J 2
(-2173 4300);
DISPLAY 0.872340 (-2173 4300);
PAINT GREEN (-2173 4300);
DISPLAY INVISIBLE (-2173 4300);
FORCEADD TAP..1
R 2
(-2175 4350);
FORCEPROP 3 LASTPIN (-2125 4350) SIG_NAME M_B_CPU0_SA_CA<5>
J 0
(-2115 4360);
DISPLAY 0.659574 (-2115 4360);
PAINT MONO (-2115 4360);
DISPLAY INVISIBLE (-2115 4360);
FORCEPROP 1 LASTPIN (-2125 4350) BN 5
J 2
(-2113 4358);
DISPLAY 0.680851 (-2113 4358);
PAINT GREEN (-2113 4358);
FORCEPROP 2 LAST CDS_LIB standard
J 0
(-2175 4350);
DISPLAY INVISIBLE (-2175 4350);
FORCEPROP 1 LAST BODY_TYPE PLUMBING
J 2
(-2175 4400);
DISPLAY 0.872340 (-2175 4400);
PAINT GREEN (-2175 4400);
DISPLAY INVISIBLE (-2175 4400);
FORCEPROP 1 LAST HDL_TAP TRUE
J 2
(-2500 4225);
DISPLAY 0.872340 (-2500 4225);
DISPLAY INVISIBLE (-2500 4225);
FORCEPROP 1 LAST PATH I114
J 2
(-2173 4350);
DISPLAY 0.872340 (-2173 4350);
PAINT GREEN (-2173 4350);
DISPLAY INVISIBLE (-2173 4350);
FORCEADD TAP..1
R 2
(-2175 4400);
FORCEPROP 3 LASTPIN (-2125 4400) SIG_NAME M_B_CPU0_SA_CA<6>
J 0
(-2115 4410);
DISPLAY 0.659574 (-2115 4410);
PAINT MONO (-2115 4410);
DISPLAY INVISIBLE (-2115 4410);
FORCEPROP 1 LASTPIN (-2125 4400) BN 6
J 2
(-2113 4408);
DISPLAY 0.680851 (-2113 4408);
PAINT GREEN (-2113 4408);
FORCEPROP 2 LAST CDS_LIB standard
J 0
(-2175 4400);
DISPLAY INVISIBLE (-2175 4400);
FORCEPROP 1 LAST BODY_TYPE PLUMBING
J 2
(-2175 4450);
DISPLAY 0.872340 (-2175 4450);
PAINT GREEN (-2175 4450);
DISPLAY INVISIBLE (-2175 4450);
FORCEPROP 1 LAST HDL_TAP TRUE
J 2
(-2500 4275);
DISPLAY 0.872340 (-2500 4275);
DISPLAY INVISIBLE (-2500 4275);
FORCEPROP 1 LAST PATH I115
J 2
(-2173 4400);
DISPLAY 0.872340 (-2173 4400);
PAINT GREEN (-2173 4400);
DISPLAY INVISIBLE (-2173 4400);
FORCEADD TAP..1
(-525 4350);
FORCEPROP 3 LASTPIN (-575 4350) SIG_NAME M_B_CPU0_SA_DQ<30>
J 0
(-565 4360);
DISPLAY 0.659574 (-565 4360);
PAINT MONO (-565 4360);
DISPLAY INVISIBLE (-565 4360);
FORCEPROP 1 LASTPIN (-575 4350) BN 30
J 0
(-587 4358);
DISPLAY 0.680851 (-587 4358);
PAINT GREEN (-587 4358);
FORCEPROP 2 LAST CDS_LIB standard
J 0
(-525 4350);
DISPLAY INVISIBLE (-525 4350);
FORCEPROP 1 LAST BODY_TYPE PLUMBING
J 0
(-525 4400);
DISPLAY 0.872340 (-525 4400);
PAINT GREEN (-525 4400);
DISPLAY INVISIBLE (-525 4400);
FORCEPROP 1 LAST HDL_TAP TRUE
J 0
(-200 4225);
DISPLAY 0.872340 (-200 4225);
DISPLAY INVISIBLE (-200 4225);
FORCEPROP 1 LAST PATH I116
J 0
(-527 4350);
DISPLAY 0.872340 (-527 4350);
PAINT GREEN (-527 4350);
DISPLAY INVISIBLE (-527 4350);
FORCEADD TAP..1
(-525 4300);
FORCEPROP 3 LASTPIN (-575 4300) SIG_NAME M_B_CPU0_SA_DQ<29>
J 0
(-565 4310);
DISPLAY 0.659574 (-565 4310);
PAINT MONO (-565 4310);
DISPLAY INVISIBLE (-565 4310);
FORCEPROP 1 LASTPIN (-575 4300) BN 29
J 0
(-587 4308);
DISPLAY 0.680851 (-587 4308);
PAINT GREEN (-587 4308);
FORCEPROP 2 LAST CDS_LIB standard
J 0
(-525 4300);
DISPLAY INVISIBLE (-525 4300);
FORCEPROP 1 LAST BODY_TYPE PLUMBING
J 0
(-525 4350);
DISPLAY 0.872340 (-525 4350);
PAINT GREEN (-525 4350);
DISPLAY INVISIBLE (-525 4350);
FORCEPROP 1 LAST HDL_TAP TRUE
J 0
(-200 4175);
DISPLAY 0.872340 (-200 4175);
DISPLAY INVISIBLE (-200 4175);
FORCEPROP 1 LAST PATH I117
J 0
(-527 4300);
DISPLAY 0.872340 (-527 4300);
PAINT GREEN (-527 4300);
DISPLAY INVISIBLE (-527 4300);
FORCEADD TAP..1
(-525 4400);
FORCEPROP 3 LASTPIN (-575 4400) SIG_NAME M_B_CPU0_SA_DQ<31>
J 0
(-565 4410);
DISPLAY 0.659574 (-565 4410);
PAINT MONO (-565 4410);
DISPLAY INVISIBLE (-565 4410);
FORCEPROP 1 LASTPIN (-575 4400) BN 31
J 0
(-587 4408);
DISPLAY 0.680851 (-587 4408);
PAINT GREEN (-587 4408);
FORCEPROP 2 LAST CDS_LIB standard
J 0
(-525 4400);
DISPLAY INVISIBLE (-525 4400);
FORCEPROP 1 LAST BODY_TYPE PLUMBING
J 0
(-525 4450);
DISPLAY 0.872340 (-525 4450);
PAINT GREEN (-525 4450);
DISPLAY INVISIBLE (-525 4450);
FORCEPROP 1 LAST HDL_TAP TRUE
J 0
(-200 4275);
DISPLAY 0.872340 (-200 4275);
DISPLAY INVISIBLE (-200 4275);
FORCEPROP 1 LAST PATH I118
J 0
(-527 4400);
DISPLAY 0.872340 (-527 4400);
PAINT GREEN (-527 4400);
DISPLAY INVISIBLE (-527 4400);
FORCEADD UNIVERSAL_GND..1
(1200 150);
FORCEPROP 3 LASTPIN (1200 200) SIG_NAME GND\g
J 0
(1210 210);
DISPLAY 0.659574 (1210 210);
PAINT MONO (1210 210);
DISPLAY INVISIBLE (1210 210);
FORCEPROP 2 LAST CDS_LIB logical_power
J 0
(1200 150);
PAINT MONO (1200 150);
DISPLAY INVISIBLE (1200 150);
FORCEPROP 1 LAST HDL_POWER GND
J 1
(1225 75);
DISPLAY 0.872340 (1225 75);
PAINT GREEN (1225 75);
DISPLAY INVISIBLE (1225 75);
FORCEPROP 1 LAST PATH I119
J 0
(1275 150);
DISPLAY 0.872340 (1275 150);
PAINT AQUA (1275 150);
DISPLAY INVISIBLE (1275 150);
FORCEADD OFFPAGE..3
R 2
(-3100 2575);
FORCEPROP 2 LAST $XR1 84 
J 0
(-3439 2575);
DISPLAY 0.638298 (-3439 2575);
PAINT MONO (-3439 2575);
FORCEPROP 2 LAST $XR0 21 
J 0
(-3349 2575);
DISPLAY 0.638298 (-3349 2575);
PAINT MONO (-3349 2575);
FORCEPROP 2 LAST CDS_LIB standard
J 0
(-3100 2575);
PAINT MONO (-3100 2575);
DISPLAY INVISIBLE (-3100 2575);
FORCEPROP 1 LAST OFFPAGE TRUE
J 2
(-3425 2450);
DISPLAY 0.872340 (-3425 2450);
DISPLAY INVISIBLE (-3425 2450);
FORCEPROP 1 LAST COMMENT_BODY TRUE
J 2
(-3050 2475);
DISPLAY 0.872340 (-3050 2475);
PAINT GREEN (-3050 2475);
DISPLAY INVISIBLE (-3050 2475);
FORCEPROP 2 LAST PATH I12
J 0
(-3050 2650);
DISPLAY 1.021277 (-3050 2650);
DISPLAY INVISIBLE (-3050 2650);
FORCEADD UNIVERSAL_GND..1
(2825 150);
FORCEPROP 3 LASTPIN (2825 200) SIG_NAME GND\g
J 0
(2835 210);
DISPLAY 0.659574 (2835 210);
PAINT MONO (2835 210);
DISPLAY INVISIBLE (2835 210);
FORCEPROP 2 LAST CDS_LIB logical_power
J 0
(2825 150);
PAINT MONO (2825 150);
DISPLAY INVISIBLE (2825 150);
FORCEPROP 1 LAST HDL_POWER GND
J 1
(2850 75);
DISPLAY 0.872340 (2850 75);
PAINT GREEN (2850 75);
DISPLAY INVISIBLE (2850 75);
FORCEPROP 1 LAST PATH I120
J 0
(2900 150);
DISPLAY 0.872340 (2900 150);
PAINT AQUA (2900 150);
DISPLAY INVISIBLE (2900 150);
FORCEADD Q_CAP..1
(1200 525);
FORCEPROP 1 LAST PART_NUMBER CH5221MEB00
J 0
(1250 375);
DISPLAY 0.978723 (1250 375);
DISPLAY INVISIBLE (1250 375);
FORCEPROP 1 LAST TOLERANCE 20%
J 0
(1250 475);
DISPLAY 0.978723 (1250 475);
FORCEPROP 1 LAST VALUE 2.2UF
J 0
(1250 575);
DISPLAY 0.978723 (1250 575);
FORCEPROP 1 LAST PACK_TYPE C0402
J 0
(1250 325);
DISPLAY 0.978723 (1250 325);
FORCEPROP 1 LAST MATERIAL X6S
J 0
(1250 425);
DISPLAY 0.978723 (1250 425);
FORCEPROP 1 LAST VOLTAGE 6.3V
J 0
(1250 525);
DISPLAY 0.978723 (1250 525);
FORCEPROP 1 LAST $LOCATION C11
J 0
(1250 625);
DISPLAY 0.978723 (1250 625);
FORCEPROP 1 LASTPIN (1200 625) $PN 1
J 0
(1210 605);
DISPLAY 0.787234 (1210 605);
FORCEPROP 1 LASTPIN (1200 425) $PN 2
J 0
(1210 405);
DISPLAY 0.787234 (1210 405);
FORCEPROP 2 LAST CDS_LIB pure_quanta
J 0
(1200 525);
PAINT MONO (1200 525);
DISPLAY INVISIBLE (1200 525);
FORCEPROP 2 LAST CDS_LOCATION C11
J 0
(1250 725);
DISPLAY 1.021277 (1250 725);
DISPLAY INVISIBLE (1250 725);
FORCEPROP 2 LAST $SEC 1
J 0
(1250 725);
DISPLAY 0.680851 (1250 725);
PAINT MONO (1250 725);
DISPLAY INVISIBLE (1250 725);
FORCEPROP 2 LAST CDS_SEC 1
J 0
(1250 725);
DISPLAY 1.021277 (1250 725);
DISPLAY INVISIBLE (1250 725);
FORCEPROP 1 LAST PATH I121
J 0
(1250 675);
DISPLAY 0.978723 (1250 675);
PAINT WHITE (1250 675);
DISPLAY INVISIBLE (1250 675);
FORCEADD VCC_CORE..1
(1200 850);
FORCEPROP 3 LASTPIN (1200 800) SIG_NAME P3V3_AUX\g
J 0
(1210 810);
DISPLAY 0.659574 (1210 810);
PAINT MONO (1210 810);
DISPLAY INVISIBLE (1210 810);
FORCEPROP 1 LAST HDL_POWER P3V3_AUX
J 1
(1200 900);
DISPLAY 1.148936 (1200 900);
PAINT GREEN (1200 900);
FORCEPROP 2 LAST CDS_LIB logical_power
J 0
(1200 850);
PAINT MONO (1200 850);
DISPLAY INVISIBLE (1200 850);
FORCEPROP 1 LAST PATH I122
J 0
(1250 875);
DISPLAY 0.872340 (1250 875);
PAINT AQUA (1250 875);
DISPLAY INVISIBLE (1250 875);
FORCEADD OFFPAGE..3
(300 2775);
FORCEPROP 2 LAST $XR1 84 
J 0
(604 2775);
DISPLAY 0.638298 (604 2775);
PAINT MONO (604 2775);
FORCEPROP 2 LAST $XR0 21 
J 0
(514 2775);
DISPLAY 0.638298 (514 2775);
PAINT MONO (514 2775);
FORCEPROP 2 LAST CDS_LIB standard
J 2
(300 2775);
DISPLAY INVISIBLE (300 2775);
FORCEPROP 1 LAST OFFPAGE TRUE
J 0
(625 2650);
DISPLAY 0.872340 (625 2650);
DISPLAY INVISIBLE (625 2650);
FORCEPROP 1 LAST COMMENT_BODY TRUE
J 0
(250 2675);
DISPLAY 0.872340 (250 2675);
PAINT GREEN (250 2675);
DISPLAY INVISIBLE (250 2675);
FORCEPROP 2 LAST PATH I123
J 0
(500 2850);
DISPLAY 1.021277 (500 2850);
DISPLAY INVISIBLE (500 2850);
FORCEADD Q_CAP..1
(2200 525);
FORCEPROP 1 LAST PART_NUMBER CH6103KEA00
J 0
(2250 375);
DISPLAY 0.978723 (2250 375);
DISPLAY INVISIBLE (2250 375);
FORCEPROP 1 LAST PACK_TYPE C0805
J 0
(2250 325);
DISPLAY 0.978723 (2250 325);
FORCEPROP 1 LAST VALUE 10UF
J 0
(2250 575);
DISPLAY 0.978723 (2250 575);
FORCEPROP 1 LAST MATERIAL X6S
J 0
(2250 425);
DISPLAY 0.978723 (2250 425);
FORCEPROP 1 LAST VOLTAGE 16V
J 0
(2250 525);
DISPLAY 0.978723 (2250 525);
FORCEPROP 1 LAST TOLERANCE 10%
J 0
(2250 475);
DISPLAY 0.978723 (2250 475);
FORCEPROP 1 LAST $LOCATION C12
J 0
(2250 625);
DISPLAY 0.978723 (2250 625);
FORCEPROP 1 LASTPIN (2200 625) $PN 1
J 0
(2210 605);
DISPLAY 0.787234 (2210 605);
FORCEPROP 1 LASTPIN (2200 425) $PN 2
J 0
(2210 405);
DISPLAY 0.787234 (2210 405);
FORCEPROP 2 LAST CDS_LIB pure_quanta
J 0
(2200 525);
PAINT MONO (2200 525);
DISPLAY INVISIBLE (2200 525);
FORCEPROP 2 LAST CDS_LOCATION C12
J 0
(2250 725);
DISPLAY 1.021277 (2250 725);
DISPLAY INVISIBLE (2250 725);
FORCEPROP 2 LAST $SEC 1
J 0
(2250 725);
DISPLAY 0.680851 (2250 725);
PAINT MONO (2250 725);
DISPLAY INVISIBLE (2250 725);
FORCEPROP 2 LAST CDS_SEC 1
J 0
(2250 725);
DISPLAY 1.021277 (2250 725);
DISPLAY INVISIBLE (2250 725);
FORCEPROP 1 LAST PATH I125
J 0
(2250 675);
DISPLAY 0.978723 (2250 675);
PAINT WHITE (2250 675);
DISPLAY INVISIBLE (2250 675);
FORCEADD VCC_CORE..1
(2200 850);
FORCEPROP 3 LASTPIN (2200 800) SIG_NAME P12V_S3_AUX_CPU0_NVDIMM\g
J 0
(2210 810);
DISPLAY 0.659574 (2210 810);
PAINT MONO (2210 810);
DISPLAY INVISIBLE (2210 810);
FORCEPROP 1 LAST HDL_POWER P12V_S3_AUX_CPU0_NVDIMM
J 1
(2200 900);
DISPLAY 1.148936 (2200 900);
PAINT GREEN (2200 900);
FORCEPROP 2 LAST CDS_LIB logical_power
J 0
(2200 850);
PAINT MONO (2200 850);
DISPLAY INVISIBLE (2200 850);
FORCEPROP 1 LAST PATH I126
J 0
(2250 875);
DISPLAY 0.872340 (2250 875);
PAINT AQUA (2250 875);
DISPLAY INVISIBLE (2250 875);
FORCEADD Q_CAP..1
(2825 525);
FORCEPROP 1 LAST PART_NUMBER CH6103KEA00
J 0
(2875 375);
DISPLAY 0.978723 (2875 375);
DISPLAY INVISIBLE (2875 375);
FORCEPROP 1 LAST TOLERANCE 10%
J 0
(2875 475);
DISPLAY 0.978723 (2875 475);
FORCEPROP 1 LAST VALUE 10UF
J 0
(2875 575);
DISPLAY 0.978723 (2875 575);
FORCEPROP 1 LAST PACK_TYPE C0805
J 0
(2875 325);
DISPLAY 0.978723 (2875 325);
FORCEPROP 1 LAST VOLTAGE 16V
J 0
(2875 525);
DISPLAY 0.978723 (2875 525);
FORCEPROP 1 LAST MATERIAL X6S
J 0
(2875 425);
DISPLAY 0.978723 (2875 425);
FORCEPROP 1 LAST $LOCATION C13
J 0
(2875 625);
DISPLAY 0.978723 (2875 625);
FORCEPROP 1 LASTPIN (2825 625) $PN 1
J 0
(2835 605);
DISPLAY 0.787234 (2835 605);
FORCEPROP 1 LASTPIN (2825 425) $PN 2
J 0
(2835 405);
DISPLAY 0.787234 (2835 405);
FORCEPROP 2 LAST CDS_LIB pure_quanta
J 0
(2825 525);
PAINT MONO (2825 525);
DISPLAY INVISIBLE (2825 525);
FORCEPROP 2 LAST CDS_LOCATION C13
J 0
(2875 725);
DISPLAY 1.021277 (2875 725);
DISPLAY INVISIBLE (2875 725);
FORCEPROP 2 LAST $SEC 1
J 0
(2875 725);
DISPLAY 0.680851 (2875 725);
PAINT MONO (2875 725);
DISPLAY INVISIBLE (2875 725);
FORCEPROP 2 LAST CDS_SEC 1
J 0
(2875 725);
DISPLAY 1.021277 (2875 725);
DISPLAY INVISIBLE (2875 725);
FORCEPROP 1 LAST PATH I127
J 0
(2875 675);
DISPLAY 0.978723 (2875 675);
PAINT WHITE (2875 675);
DISPLAY INVISIBLE (2875 675);
FORCEADD TAP..1
(2225 2450);
FORCEPROP 3 LASTPIN (2175 2450) SIG_NAME M_B_CPU0_SB_DQS_DP<0>
J 0
(2185 2460);
DISPLAY 0.659574 (2185 2460);
PAINT MONO (2185 2460);
DISPLAY INVISIBLE (2185 2460);
FORCEPROP 1 LASTPIN (2175 2450) BN 0
J 0
(2163 2458);
DISPLAY 0.680851 (2163 2458);
PAINT GREEN (2163 2458);
FORCEPROP 2 LAST CDS_LIB standard
J 0
(2225 2450);
PAINT MONO (2225 2450);
DISPLAY INVISIBLE (2225 2450);
FORCEPROP 1 LAST BODY_TYPE PLUMBING
J 0
(2225 2500);
DISPLAY 0.872340 (2225 2500);
PAINT GREEN (2225 2500);
DISPLAY INVISIBLE (2225 2500);
FORCEPROP 1 LAST HDL_TAP TRUE
J 0
(2550 2325);
DISPLAY 0.872340 (2550 2325);
DISPLAY INVISIBLE (2550 2325);
FORCEPROP 1 LAST PATH I128
J 0
(2223 2450);
DISPLAY 0.872340 (2223 2450);
PAINT GREEN (2223 2450);
DISPLAY INVISIBLE (2223 2450);
FORCEADD TAP..1
(2400 2500);
FORCEPROP 3 LASTPIN (2350 2500) SIG_NAME M_B_CPU0_SB_DQS_DN<1>
J 0
(2360 2510);
DISPLAY 0.659574 (2360 2510);
PAINT MONO (2360 2510);
DISPLAY INVISIBLE (2360 2510);
FORCEPROP 1 LASTPIN (2350 2500) BN 1
J 0
(2338 2508);
DISPLAY 0.680851 (2338 2508);
PAINT GREEN (2338 2508);
FORCEPROP 2 LAST CDS_LIB standard
J 0
(2400 2500);
DISPLAY INVISIBLE (2400 2500);
FORCEPROP 1 LAST BODY_TYPE PLUMBING
J 0
(2400 2550);
DISPLAY 0.872340 (2400 2550);
PAINT GREEN (2400 2550);
DISPLAY INVISIBLE (2400 2550);
FORCEPROP 1 LAST HDL_TAP TRUE
J 0
(2725 2375);
DISPLAY 0.872340 (2725 2375);
DISPLAY INVISIBLE (2725 2375);
FORCEPROP 1 LAST PATH I129
J 0
(2398 2500);
DISPLAY 0.872340 (2398 2500);
PAINT GREEN (2398 2500);
DISPLAY INVISIBLE (2398 2500);
FORCEADD OFFPAGE..3
R 2
(-3100 3025);
FORCEPROP 2 LAST $XR1 84 
J 0
(-3439 3025);
DISPLAY 0.638298 (-3439 3025);
PAINT MONO (-3439 3025);
FORCEPROP 2 LAST $XR0 21 
J 0
(-3349 3025);
DISPLAY 0.638298 (-3349 3025);
PAINT MONO (-3349 3025);
FORCEPROP 2 LAST CDS_LIB standard
J 0
(-3100 3025);
PAINT MONO (-3100 3025);
DISPLAY INVISIBLE (-3100 3025);
FORCEPROP 1 LAST OFFPAGE TRUE
J 2
(-3425 2900);
DISPLAY 0.872340 (-3425 2900);
DISPLAY INVISIBLE (-3425 2900);
FORCEPROP 1 LAST COMMENT_BODY TRUE
J 2
(-3050 2925);
DISPLAY 0.872340 (-3050 2925);
PAINT GREEN (-3050 2925);
DISPLAY INVISIBLE (-3050 2925);
FORCEPROP 2 LAST PATH I13
J 0
(-3050 3100);
DISPLAY 1.021277 (-3050 3100);
DISPLAY INVISIBLE (-3050 3100);
FORCEADD TAP..1
(2400 2400);
FORCEPROP 3 LASTPIN (2350 2400) SIG_NAME M_B_CPU0_SB_DQS_DN<0>
J 0
(2360 2410);
DISPLAY 0.659574 (2360 2410);
PAINT MONO (2360 2410);
DISPLAY INVISIBLE (2360 2410);
FORCEPROP 1 LASTPIN (2350 2400) BN 0
J 0
(2338 2408);
DISPLAY 0.680851 (2338 2408);
PAINT GREEN (2338 2408);
FORCEPROP 2 LAST CDS_LIB standard
J 0
(2400 2400);
PAINT MONO (2400 2400);
DISPLAY INVISIBLE (2400 2400);
FORCEPROP 1 LAST BODY_TYPE PLUMBING
J 0
(2400 2450);
DISPLAY 0.872340 (2400 2450);
PAINT GREEN (2400 2450);
DISPLAY INVISIBLE (2400 2450);
FORCEPROP 1 LAST HDL_TAP TRUE
J 0
(2725 2275);
DISPLAY 0.872340 (2725 2275);
DISPLAY INVISIBLE (2725 2275);
FORCEPROP 1 LAST PATH I130
J 0
(2398 2400);
DISPLAY 0.872340 (2398 2400);
PAINT GREEN (2398 2400);
DISPLAY INVISIBLE (2398 2400);
FORCEADD TAP..1
(2225 2550);
FORCEPROP 3 LASTPIN (2175 2550) SIG_NAME M_B_CPU0_SB_DQS_DP<1>
J 0
(2185 2560);
DISPLAY 0.659574 (2185 2560);
PAINT MONO (2185 2560);
DISPLAY INVISIBLE (2185 2560);
FORCEPROP 1 LASTPIN (2175 2550) BN 1
J 0
(2163 2558);
DISPLAY 0.680851 (2163 2558);
PAINT GREEN (2163 2558);
FORCEPROP 2 LAST CDS_LIB standard
J 0
(2225 2550);
DISPLAY INVISIBLE (2225 2550);
FORCEPROP 1 LAST BODY_TYPE PLUMBING
J 0
(2225 2600);
DISPLAY 0.872340 (2225 2600);
PAINT GREEN (2225 2600);
DISPLAY INVISIBLE (2225 2600);
FORCEPROP 1 LAST HDL_TAP TRUE
J 0
(2550 2425);
DISPLAY 0.872340 (2550 2425);
DISPLAY INVISIBLE (2550 2425);
FORCEPROP 1 LAST PATH I131
J 0
(2223 2550);
DISPLAY 0.872340 (2223 2550);
PAINT GREEN (2223 2550);
DISPLAY INVISIBLE (2223 2550);
FORCEADD TAP..1
(2225 2650);
FORCEPROP 3 LASTPIN (2175 2650) SIG_NAME M_B_CPU0_SB_DQS_DP<2>
J 0
(2185 2660);
DISPLAY 0.659574 (2185 2660);
PAINT MONO (2185 2660);
DISPLAY INVISIBLE (2185 2660);
FORCEPROP 1 LASTPIN (2175 2650) BN 2
J 0
(2163 2658);
DISPLAY 0.680851 (2163 2658);
PAINT GREEN (2163 2658);
FORCEPROP 2 LAST CDS_LIB standard
J 0
(2225 2650);
DISPLAY INVISIBLE (2225 2650);
FORCEPROP 1 LAST BODY_TYPE PLUMBING
J 0
(2225 2700);
DISPLAY 0.872340 (2225 2700);
PAINT GREEN (2225 2700);
DISPLAY INVISIBLE (2225 2700);
FORCEPROP 1 LAST HDL_TAP TRUE
J 0
(2550 2525);
DISPLAY 0.872340 (2550 2525);
DISPLAY INVISIBLE (2550 2525);
FORCEPROP 1 LAST PATH I132
J 0
(2223 2650);
DISPLAY 0.872340 (2223 2650);
PAINT GREEN (2223 2650);
DISPLAY INVISIBLE (2223 2650);
FORCEADD TAP..1
(2225 2750);
FORCEPROP 3 LASTPIN (2175 2750) SIG_NAME M_B_CPU0_SB_DQS_DP<3>
J 0
(2185 2760);
DISPLAY 0.659574 (2185 2760);
PAINT MONO (2185 2760);
DISPLAY INVISIBLE (2185 2760);
FORCEPROP 1 LASTPIN (2175 2750) BN 3
J 0
(2163 2758);
DISPLAY 0.680851 (2163 2758);
PAINT GREEN (2163 2758);
FORCEPROP 2 LAST CDS_LIB standard
J 0
(2225 2750);
PAINT MONO (2225 2750);
DISPLAY INVISIBLE (2225 2750);
FORCEPROP 1 LAST BODY_TYPE PLUMBING
J 0
(2225 2800);
DISPLAY 0.872340 (2225 2800);
PAINT GREEN (2225 2800);
DISPLAY INVISIBLE (2225 2800);
FORCEPROP 1 LAST HDL_TAP TRUE
J 0
(2550 2625);
DISPLAY 0.872340 (2550 2625);
DISPLAY INVISIBLE (2550 2625);
FORCEPROP 1 LAST PATH I133
J 0
(2223 2750);
DISPLAY 0.872340 (2223 2750);
PAINT GREEN (2223 2750);
DISPLAY INVISIBLE (2223 2750);
FORCEADD TAP..1
(2400 2600);
FORCEPROP 3 LASTPIN (2350 2600) SIG_NAME M_B_CPU0_SB_DQS_DN<2>
J 0
(2360 2610);
DISPLAY 0.659574 (2360 2610);
PAINT MONO (2360 2610);
DISPLAY INVISIBLE (2360 2610);
FORCEPROP 1 LASTPIN (2350 2600) BN 2
J 0
(2338 2608);
DISPLAY 0.680851 (2338 2608);
PAINT GREEN (2338 2608);
FORCEPROP 2 LAST CDS_LIB standard
J 0
(2400 2600);
DISPLAY INVISIBLE (2400 2600);
FORCEPROP 1 LAST BODY_TYPE PLUMBING
J 0
(2400 2650);
DISPLAY 0.872340 (2400 2650);
PAINT GREEN (2400 2650);
DISPLAY INVISIBLE (2400 2650);
FORCEPROP 1 LAST HDL_TAP TRUE
J 0
(2725 2475);
DISPLAY 0.872340 (2725 2475);
DISPLAY INVISIBLE (2725 2475);
FORCEPROP 1 LAST PATH I134
J 0
(2398 2600);
DISPLAY 0.872340 (2398 2600);
PAINT GREEN (2398 2600);
DISPLAY INVISIBLE (2398 2600);
FORCEADD TAP..1
(2400 2700);
FORCEPROP 3 LASTPIN (2350 2700) SIG_NAME M_B_CPU0_SB_DQS_DN<3>
J 0
(2360 2710);
DISPLAY 0.659574 (2360 2710);
PAINT MONO (2360 2710);
DISPLAY INVISIBLE (2360 2710);
FORCEPROP 1 LASTPIN (2350 2700) BN 3
J 0
(2338 2708);
DISPLAY 0.680851 (2338 2708);
PAINT GREEN (2338 2708);
FORCEPROP 2 LAST CDS_LIB standard
J 0
(2400 2700);
PAINT MONO (2400 2700);
DISPLAY INVISIBLE (2400 2700);
FORCEPROP 1 LAST BODY_TYPE PLUMBING
J 0
(2400 2750);
DISPLAY 0.872340 (2400 2750);
PAINT GREEN (2400 2750);
DISPLAY INVISIBLE (2400 2750);
FORCEPROP 1 LAST HDL_TAP TRUE
J 0
(2725 2575);
DISPLAY 0.872340 (2725 2575);
DISPLAY INVISIBLE (2725 2575);
FORCEPROP 1 LAST PATH I135
J 0
(2398 2700);
DISPLAY 0.872340 (2398 2700);
PAINT GREEN (2398 2700);
DISPLAY INVISIBLE (2398 2700);
FORCEADD TAP..1
(2225 2850);
FORCEPROP 3 LASTPIN (2175 2850) SIG_NAME M_B_CPU0_SB_DQS_DP<4>
J 0
(2185 2860);
DISPLAY 0.659574 (2185 2860);
PAINT MONO (2185 2860);
DISPLAY INVISIBLE (2185 2860);
FORCEPROP 1 LASTPIN (2175 2850) BN 4
J 0
(2163 2858);
DISPLAY 0.680851 (2163 2858);
PAINT GREEN (2163 2858);
FORCEPROP 2 LAST CDS_LIB standard
J 0
(2225 2850);
PAINT MONO (2225 2850);
DISPLAY INVISIBLE (2225 2850);
FORCEPROP 1 LAST BODY_TYPE PLUMBING
J 0
(2225 2900);
DISPLAY 0.872340 (2225 2900);
PAINT GREEN (2225 2900);
DISPLAY INVISIBLE (2225 2900);
FORCEPROP 1 LAST HDL_TAP TRUE
J 0
(2550 2725);
DISPLAY 0.872340 (2550 2725);
DISPLAY INVISIBLE (2550 2725);
FORCEPROP 1 LAST PATH I136
J 0
(2223 2850);
DISPLAY 0.872340 (2223 2850);
PAINT GREEN (2223 2850);
DISPLAY INVISIBLE (2223 2850);
FORCEADD TAP..1
(2225 2950);
FORCEPROP 3 LASTPIN (2175 2950) SIG_NAME M_B_CPU0_SB_DQS_DP<5>
J 0
(2185 2960);
DISPLAY 0.659574 (2185 2960);
PAINT MONO (2185 2960);
DISPLAY INVISIBLE (2185 2960);
FORCEPROP 1 LASTPIN (2175 2950) BN 5
J 0
(2163 2958);
DISPLAY 0.680851 (2163 2958);
PAINT GREEN (2163 2958);
FORCEPROP 2 LAST CDS_LIB standard
J 0
(2225 2950);
DISPLAY INVISIBLE (2225 2950);
FORCEPROP 1 LAST BODY_TYPE PLUMBING
J 0
(2225 3000);
DISPLAY 0.872340 (2225 3000);
PAINT GREEN (2225 3000);
DISPLAY INVISIBLE (2225 3000);
FORCEPROP 1 LAST HDL_TAP TRUE
J 0
(2550 2825);
DISPLAY 0.872340 (2550 2825);
DISPLAY INVISIBLE (2550 2825);
FORCEPROP 1 LAST PATH I137
J 0
(2223 2950);
DISPLAY 0.872340 (2223 2950);
PAINT GREEN (2223 2950);
DISPLAY INVISIBLE (2223 2950);
FORCEADD TAP..1
(2400 2800);
FORCEPROP 3 LASTPIN (2350 2800) SIG_NAME M_B_CPU0_SB_DQS_DN<4>
J 0
(2360 2810);
DISPLAY 0.659574 (2360 2810);
PAINT MONO (2360 2810);
DISPLAY INVISIBLE (2360 2810);
FORCEPROP 1 LASTPIN (2350 2800) BN 4
J 0
(2338 2808);
DISPLAY 0.680851 (2338 2808);
PAINT GREEN (2338 2808);
FORCEPROP 2 LAST CDS_LIB standard
J 0
(2400 2800);
PAINT MONO (2400 2800);
DISPLAY INVISIBLE (2400 2800);
FORCEPROP 1 LAST BODY_TYPE PLUMBING
J 0
(2400 2850);
DISPLAY 0.872340 (2400 2850);
PAINT GREEN (2400 2850);
DISPLAY INVISIBLE (2400 2850);
FORCEPROP 1 LAST HDL_TAP TRUE
J 0
(2725 2675);
DISPLAY 0.872340 (2725 2675);
DISPLAY INVISIBLE (2725 2675);
FORCEPROP 1 LAST PATH I138
J 0
(2398 2800);
DISPLAY 0.872340 (2398 2800);
PAINT GREEN (2398 2800);
DISPLAY INVISIBLE (2398 2800);
FORCEADD TAP..1
(2400 3000);
FORCEPROP 3 LASTPIN (2350 3000) SIG_NAME M_B_CPU0_SB_DQS_DN<6>
J 0
(2360 3010);
DISPLAY 0.659574 (2360 3010);
PAINT MONO (2360 3010);
DISPLAY INVISIBLE (2360 3010);
FORCEPROP 1 LASTPIN (2350 3000) BN 6
J 0
(2338 3008);
DISPLAY 0.680851 (2338 3008);
PAINT GREEN (2338 3008);
FORCEPROP 2 LAST CDS_LIB standard
J 0
(2400 3000);
DISPLAY INVISIBLE (2400 3000);
FORCEPROP 1 LAST BODY_TYPE PLUMBING
J 0
(2400 3050);
DISPLAY 0.872340 (2400 3050);
PAINT GREEN (2400 3050);
DISPLAY INVISIBLE (2400 3050);
FORCEPROP 1 LAST HDL_TAP TRUE
J 0
(2725 2875);
DISPLAY 0.872340 (2725 2875);
DISPLAY INVISIBLE (2725 2875);
FORCEPROP 1 LAST PATH I139
J 0
(2398 3000);
DISPLAY 0.872340 (2398 3000);
PAINT GREEN (2398 3000);
DISPLAY INVISIBLE (2398 3000);
FORCEADD OFFPAGE..1
(-3100 3100);
FORCEPROP 2 LAST $XR0 21 
J 0
(-3321 3100);
DISPLAY 0.638298 (-3321 3100);
PAINT MONO (-3321 3100);
FORCEPROP 2 LAST CDS_LIB standard
J 0
(-3100 3100);
PAINT MONO (-3100 3100);
DISPLAY INVISIBLE (-3100 3100);
FORCEPROP 1 LAST OFFPAGE TRUE
J 0
(-2775 2975);
DISPLAY 0.872340 (-2775 2975);
DISPLAY INVISIBLE (-2775 2975);
FORCEPROP 1 LAST COMMENT_BODY TRUE
J 0
(-2975 3000);
DISPLAY 0.872340 (-2975 3000);
PAINT GREEN (-2975 3000);
DISPLAY INVISIBLE (-2975 3000);
FORCEPROP 2 LAST PATH I14
J 0
(-3050 3175);
DISPLAY 1.021277 (-3050 3175);
DISPLAY INVISIBLE (-3050 3175);
FORCEADD TAP..1
(2400 2900);
FORCEPROP 3 LASTPIN (2350 2900) SIG_NAME M_B_CPU0_SB_DQS_DN<5>
J 0
(2360 2910);
DISPLAY 0.659574 (2360 2910);
PAINT MONO (2360 2910);
DISPLAY INVISIBLE (2360 2910);
FORCEPROP 1 LASTPIN (2350 2900) BN 5
J 0
(2338 2908);
DISPLAY 0.680851 (2338 2908);
PAINT GREEN (2338 2908);
FORCEPROP 2 LAST CDS_LIB standard
J 0
(2400 2900);
DISPLAY INVISIBLE (2400 2900);
FORCEPROP 1 LAST BODY_TYPE PLUMBING
J 0
(2400 2950);
DISPLAY 0.872340 (2400 2950);
PAINT GREEN (2400 2950);
DISPLAY INVISIBLE (2400 2950);
FORCEPROP 1 LAST HDL_TAP TRUE
J 0
(2725 2775);
DISPLAY 0.872340 (2725 2775);
DISPLAY INVISIBLE (2725 2775);
FORCEPROP 1 LAST PATH I140
J 0
(2398 2900);
DISPLAY 0.872340 (2398 2900);
PAINT GREEN (2398 2900);
DISPLAY INVISIBLE (2398 2900);
FORCEADD TAP..1
(2225 3050);
FORCEPROP 3 LASTPIN (2175 3050) SIG_NAME M_B_CPU0_SB_DQS_DP<6>
J 0
(2185 3060);
DISPLAY 0.659574 (2185 3060);
PAINT MONO (2185 3060);
DISPLAY INVISIBLE (2185 3060);
FORCEPROP 1 LASTPIN (2175 3050) BN 6
J 0
(2163 3058);
DISPLAY 0.680851 (2163 3058);
PAINT GREEN (2163 3058);
FORCEPROP 2 LAST CDS_LIB standard
J 0
(2225 3050);
DISPLAY INVISIBLE (2225 3050);
FORCEPROP 1 LAST BODY_TYPE PLUMBING
J 0
(2225 3100);
DISPLAY 0.872340 (2225 3100);
PAINT GREEN (2225 3100);
DISPLAY INVISIBLE (2225 3100);
FORCEPROP 1 LAST HDL_TAP TRUE
J 0
(2550 2925);
DISPLAY 0.872340 (2550 2925);
DISPLAY INVISIBLE (2550 2925);
FORCEPROP 1 LAST PATH I141
J 0
(2223 3050);
DISPLAY 0.872340 (2223 3050);
PAINT GREEN (2223 3050);
DISPLAY INVISIBLE (2223 3050);
FORCEADD TAP..1
(2225 3150);
FORCEPROP 3 LASTPIN (2175 3150) SIG_NAME M_B_CPU0_SB_DQS_DP<7>
J 0
(2185 3160);
DISPLAY 0.659574 (2185 3160);
PAINT MONO (2185 3160);
DISPLAY INVISIBLE (2185 3160);
FORCEPROP 1 LASTPIN (2175 3150) BN 7
J 0
(2163 3158);
DISPLAY 0.680851 (2163 3158);
PAINT GREEN (2163 3158);
FORCEPROP 2 LAST CDS_LIB standard
J 0
(2225 3150);
DISPLAY INVISIBLE (2225 3150);
FORCEPROP 1 LAST BODY_TYPE PLUMBING
J 0
(2225 3200);
DISPLAY 0.872340 (2225 3200);
PAINT GREEN (2225 3200);
DISPLAY INVISIBLE (2225 3200);
FORCEPROP 1 LAST HDL_TAP TRUE
J 0
(2550 3025);
DISPLAY 0.872340 (2550 3025);
DISPLAY INVISIBLE (2550 3025);
FORCEPROP 1 LAST PATH I142
J 0
(2223 3150);
DISPLAY 0.872340 (2223 3150);
PAINT GREEN (2223 3150);
DISPLAY INVISIBLE (2223 3150);
FORCEADD TAP..1
(2225 3250);
FORCEPROP 3 LASTPIN (2175 3250) SIG_NAME M_B_CPU0_SB_DQS_DP<8>
J 0
(2185 3260);
DISPLAY 0.659574 (2185 3260);
PAINT MONO (2185 3260);
DISPLAY INVISIBLE (2185 3260);
FORCEPROP 1 LASTPIN (2175 3250) BN 8
J 0
(2163 3258);
DISPLAY 0.680851 (2163 3258);
PAINT GREEN (2163 3258);
FORCEPROP 2 LAST CDS_LIB standard
J 0
(2225 3250);
DISPLAY INVISIBLE (2225 3250);
FORCEPROP 1 LAST BODY_TYPE PLUMBING
J 0
(2225 3300);
DISPLAY 0.872340 (2225 3300);
PAINT GREEN (2225 3300);
DISPLAY INVISIBLE (2225 3300);
FORCEPROP 1 LAST HDL_TAP TRUE
J 0
(2550 3125);
DISPLAY 0.872340 (2550 3125);
DISPLAY INVISIBLE (2550 3125);
FORCEPROP 1 LAST PATH I143
J 0
(2223 3250);
DISPLAY 0.872340 (2223 3250);
PAINT GREEN (2223 3250);
DISPLAY INVISIBLE (2223 3250);
FORCEADD TAP..1
(2400 3100);
FORCEPROP 3 LASTPIN (2350 3100) SIG_NAME M_B_CPU0_SB_DQS_DN<7>
J 0
(2360 3110);
DISPLAY 0.659574 (2360 3110);
PAINT MONO (2360 3110);
DISPLAY INVISIBLE (2360 3110);
FORCEPROP 1 LASTPIN (2350 3100) BN 7
J 0
(2338 3108);
DISPLAY 0.680851 (2338 3108);
PAINT GREEN (2338 3108);
FORCEPROP 2 LAST CDS_LIB standard
J 0
(2400 3100);
DISPLAY INVISIBLE (2400 3100);
FORCEPROP 1 LAST BODY_TYPE PLUMBING
J 0
(2400 3150);
DISPLAY 0.872340 (2400 3150);
PAINT GREEN (2400 3150);
DISPLAY INVISIBLE (2400 3150);
FORCEPROP 1 LAST HDL_TAP TRUE
J 0
(2725 2975);
DISPLAY 0.872340 (2725 2975);
DISPLAY INVISIBLE (2725 2975);
FORCEPROP 1 LAST PATH I144
J 0
(2398 3100);
DISPLAY 0.872340 (2398 3100);
PAINT GREEN (2398 3100);
DISPLAY INVISIBLE (2398 3100);
FORCEADD TAP..1
(2400 3200);
FORCEPROP 3 LASTPIN (2350 3200) SIG_NAME M_B_CPU0_SB_DQS_DN<8>
J 0
(2360 3210);
DISPLAY 0.659574 (2360 3210);
PAINT MONO (2360 3210);
DISPLAY INVISIBLE (2360 3210);
FORCEPROP 1 LASTPIN (2350 3200) BN 8
J 0
(2338 3208);
DISPLAY 0.680851 (2338 3208);
PAINT GREEN (2338 3208);
FORCEPROP 2 LAST CDS_LIB standard
J 0
(2400 3200);
DISPLAY INVISIBLE (2400 3200);
FORCEPROP 1 LAST BODY_TYPE PLUMBING
J 0
(2400 3250);
DISPLAY 0.872340 (2400 3250);
PAINT GREEN (2400 3250);
DISPLAY INVISIBLE (2400 3250);
FORCEPROP 1 LAST HDL_TAP TRUE
J 0
(2725 3075);
DISPLAY 0.872340 (2725 3075);
DISPLAY INVISIBLE (2725 3075);
FORCEPROP 1 LAST PATH I145
J 0
(2398 3200);
DISPLAY 0.872340 (2398 3200);
PAINT GREEN (2398 3200);
DISPLAY INVISIBLE (2398 3200);
FORCEADD TAP..1
(2225 3350);
FORCEPROP 3 LASTPIN (2175 3350) SIG_NAME M_B_CPU0_SB_DQS_DP<9>
J 0
(2185 3360);
DISPLAY 0.659574 (2185 3360);
PAINT MONO (2185 3360);
DISPLAY INVISIBLE (2185 3360);
FORCEPROP 1 LASTPIN (2175 3350) BN 9
J 0
(2163 3358);
DISPLAY 0.680851 (2163 3358);
PAINT GREEN (2163 3358);
FORCEPROP 2 LAST CDS_LIB standard
J 0
(2225 3350);
DISPLAY INVISIBLE (2225 3350);
FORCEPROP 1 LAST BODY_TYPE PLUMBING
J 0
(2225 3400);
DISPLAY 0.872340 (2225 3400);
PAINT GREEN (2225 3400);
DISPLAY INVISIBLE (2225 3400);
FORCEPROP 1 LAST HDL_TAP TRUE
J 0
(2550 3225);
DISPLAY 0.872340 (2550 3225);
DISPLAY INVISIBLE (2550 3225);
FORCEPROP 1 LAST PATH I146
J 0
(2223 3350);
DISPLAY 0.872340 (2223 3350);
PAINT GREEN (2223 3350);
DISPLAY INVISIBLE (2223 3350);
FORCEADD TAP..1
(2225 3500);
FORCEPROP 3 LASTPIN (2175 3500) SIG_NAME M_B_CPU0_SA_DQS_DP<0>
J 0
(2185 3510);
DISPLAY 0.659574 (2185 3510);
PAINT MONO (2185 3510);
DISPLAY INVISIBLE (2185 3510);
FORCEPROP 1 LASTPIN (2175 3500) BN 0
J 0
(2163 3508);
DISPLAY 0.680851 (2163 3508);
PAINT GREEN (2163 3508);
FORCEPROP 2 LAST CDS_LIB standard
J 0
(2225 3500);
PAINT MONO (2225 3500);
DISPLAY INVISIBLE (2225 3500);
FORCEPROP 1 LAST BODY_TYPE PLUMBING
J 0
(2225 3550);
DISPLAY 0.872340 (2225 3550);
PAINT GREEN (2225 3550);
DISPLAY INVISIBLE (2225 3550);
FORCEPROP 1 LAST HDL_TAP TRUE
J 0
(2550 3375);
DISPLAY 0.872340 (2550 3375);
DISPLAY INVISIBLE (2550 3375);
FORCEPROP 1 LAST PATH I147
J 0
(2223 3500);
DISPLAY 0.872340 (2223 3500);
PAINT GREEN (2223 3500);
DISPLAY INVISIBLE (2223 3500);
FORCEADD TAP..1
(2400 3450);
FORCEPROP 3 LASTPIN (2350 3450) SIG_NAME M_B_CPU0_SA_DQS_DN<0>
J 0
(2360 3460);
DISPLAY 0.659574 (2360 3460);
PAINT MONO (2360 3460);
DISPLAY INVISIBLE (2360 3460);
FORCEPROP 1 LASTPIN (2350 3450) BN 0
J 0
(2338 3458);
DISPLAY 0.680851 (2338 3458);
PAINT GREEN (2338 3458);
FORCEPROP 2 LAST CDS_LIB standard
J 0
(2400 3450);
PAINT MONO (2400 3450);
DISPLAY INVISIBLE (2400 3450);
FORCEPROP 1 LAST BODY_TYPE PLUMBING
J 0
(2400 3500);
DISPLAY 0.872340 (2400 3500);
PAINT GREEN (2400 3500);
DISPLAY INVISIBLE (2400 3500);
FORCEPROP 1 LAST HDL_TAP TRUE
J 0
(2725 3325);
DISPLAY 0.872340 (2725 3325);
DISPLAY INVISIBLE (2725 3325);
FORCEPROP 1 LAST PATH I148
J 0
(2398 3450);
DISPLAY 0.872340 (2398 3450);
PAINT GREEN (2398 3450);
DISPLAY INVISIBLE (2398 3450);
FORCEADD TAP..1
(2400 3300);
FORCEPROP 3 LASTPIN (2350 3300) SIG_NAME M_B_CPU0_SB_DQS_DN<9>
J 0
(2360 3310);
DISPLAY 0.659574 (2360 3310);
PAINT MONO (2360 3310);
DISPLAY INVISIBLE (2360 3310);
FORCEPROP 1 LASTPIN (2350 3300) BN 9
J 0
(2338 3308);
DISPLAY 0.680851 (2338 3308);
PAINT GREEN (2338 3308);
FORCEPROP 2 LAST CDS_LIB standard
J 0
(2400 3300);
DISPLAY INVISIBLE (2400 3300);
FORCEPROP 1 LAST BODY_TYPE PLUMBING
J 0
(2400 3350);
DISPLAY 0.872340 (2400 3350);
PAINT GREEN (2400 3350);
DISPLAY INVISIBLE (2400 3350);
FORCEPROP 1 LAST HDL_TAP TRUE
J 0
(2725 3175);
DISPLAY 0.872340 (2725 3175);
DISPLAY INVISIBLE (2725 3175);
FORCEPROP 1 LAST PATH I149
J 0
(2398 3300);
DISPLAY 0.872340 (2398 3300);
PAINT GREEN (2398 3300);
DISPLAY INVISIBLE (2398 3300);
FORCEADD OFFPAGE..1
(-3100 3150);
FORCEPROP 2 LAST $XR0 21 
J 0
(-3321 3150);
DISPLAY 0.638298 (-3321 3150);
PAINT MONO (-3321 3150);
FORCEPROP 2 LAST CDS_LIB standard
J 0
(-3100 3150);
PAINT MONO (-3100 3150);
DISPLAY INVISIBLE (-3100 3150);
FORCEPROP 1 LAST OFFPAGE TRUE
J 0
(-2775 3025);
DISPLAY 0.872340 (-2775 3025);
DISPLAY INVISIBLE (-2775 3025);
FORCEPROP 1 LAST COMMENT_BODY TRUE
J 0
(-2975 3050);
DISPLAY 0.872340 (-2975 3050);
PAINT GREEN (-2975 3050);
DISPLAY INVISIBLE (-2975 3050);
FORCEPROP 2 LAST PATH I15
J 0
(-3050 3225);
DISPLAY 1.021277 (-3050 3225);
DISPLAY INVISIBLE (-3050 3225);
FORCEADD TAP..1
(2225 3600);
FORCEPROP 3 LASTPIN (2175 3600) SIG_NAME M_B_CPU0_SA_DQS_DP<1>
J 0
(2185 3610);
DISPLAY 0.659574 (2185 3610);
PAINT MONO (2185 3610);
DISPLAY INVISIBLE (2185 3610);
FORCEPROP 1 LASTPIN (2175 3600) BN 1
J 0
(2163 3608);
DISPLAY 0.680851 (2163 3608);
PAINT GREEN (2163 3608);
FORCEPROP 2 LAST CDS_LIB standard
J 0
(2225 3600);
DISPLAY INVISIBLE (2225 3600);
FORCEPROP 1 LAST BODY_TYPE PLUMBING
J 0
(2225 3650);
DISPLAY 0.872340 (2225 3650);
PAINT GREEN (2225 3650);
DISPLAY INVISIBLE (2225 3650);
FORCEPROP 1 LAST HDL_TAP TRUE
J 0
(2550 3475);
DISPLAY 0.872340 (2550 3475);
DISPLAY INVISIBLE (2550 3475);
FORCEPROP 1 LAST PATH I150
J 0
(2223 3600);
DISPLAY 0.872340 (2223 3600);
PAINT GREEN (2223 3600);
DISPLAY INVISIBLE (2223 3600);
FORCEADD TAP..1
(2225 3700);
FORCEPROP 3 LASTPIN (2175 3700) SIG_NAME M_B_CPU0_SA_DQS_DP<2>
J 0
(2185 3710);
DISPLAY 0.659574 (2185 3710);
PAINT MONO (2185 3710);
DISPLAY INVISIBLE (2185 3710);
FORCEPROP 1 LASTPIN (2175 3700) BN 2
J 0
(2163 3708);
DISPLAY 0.680851 (2163 3708);
PAINT GREEN (2163 3708);
FORCEPROP 2 LAST CDS_LIB standard
J 0
(2225 3700);
DISPLAY INVISIBLE (2225 3700);
FORCEPROP 1 LAST BODY_TYPE PLUMBING
J 0
(2225 3750);
DISPLAY 0.872340 (2225 3750);
PAINT GREEN (2225 3750);
DISPLAY INVISIBLE (2225 3750);
FORCEPROP 1 LAST HDL_TAP TRUE
J 0
(2550 3575);
DISPLAY 0.872340 (2550 3575);
DISPLAY INVISIBLE (2550 3575);
FORCEPROP 1 LAST PATH I151
J 0
(2223 3700);
DISPLAY 0.872340 (2223 3700);
PAINT GREEN (2223 3700);
DISPLAY INVISIBLE (2223 3700);
FORCEADD TAP..1
(2400 3550);
FORCEPROP 3 LASTPIN (2350 3550) SIG_NAME M_B_CPU0_SA_DQS_DN<1>
J 0
(2360 3560);
DISPLAY 0.659574 (2360 3560);
PAINT MONO (2360 3560);
DISPLAY INVISIBLE (2360 3560);
FORCEPROP 1 LASTPIN (2350 3550) BN 1
J 0
(2338 3558);
DISPLAY 0.680851 (2338 3558);
PAINT GREEN (2338 3558);
FORCEPROP 2 LAST CDS_LIB standard
J 0
(2400 3550);
DISPLAY INVISIBLE (2400 3550);
FORCEPROP 1 LAST BODY_TYPE PLUMBING
J 0
(2400 3600);
DISPLAY 0.872340 (2400 3600);
PAINT GREEN (2400 3600);
DISPLAY INVISIBLE (2400 3600);
FORCEPROP 1 LAST HDL_TAP TRUE
J 0
(2725 3425);
DISPLAY 0.872340 (2725 3425);
DISPLAY INVISIBLE (2725 3425);
FORCEPROP 1 LAST PATH I152
J 0
(2398 3550);
DISPLAY 0.872340 (2398 3550);
PAINT GREEN (2398 3550);
DISPLAY INVISIBLE (2398 3550);
FORCEADD TAP..1
(2400 3650);
FORCEPROP 3 LASTPIN (2350 3650) SIG_NAME M_B_CPU0_SA_DQS_DN<2>
J 0
(2360 3660);
DISPLAY 0.659574 (2360 3660);
PAINT MONO (2360 3660);
DISPLAY INVISIBLE (2360 3660);
FORCEPROP 1 LASTPIN (2350 3650) BN 2
J 0
(2338 3658);
DISPLAY 0.680851 (2338 3658);
PAINT GREEN (2338 3658);
FORCEPROP 2 LAST CDS_LIB standard
J 0
(2400 3650);
DISPLAY INVISIBLE (2400 3650);
FORCEPROP 1 LAST BODY_TYPE PLUMBING
J 0
(2400 3700);
DISPLAY 0.872340 (2400 3700);
PAINT GREEN (2400 3700);
DISPLAY INVISIBLE (2400 3700);
FORCEPROP 1 LAST HDL_TAP TRUE
J 0
(2725 3525);
DISPLAY 0.872340 (2725 3525);
DISPLAY INVISIBLE (2725 3525);
FORCEPROP 1 LAST PATH I153
J 0
(2398 3650);
DISPLAY 0.872340 (2398 3650);
PAINT GREEN (2398 3650);
DISPLAY INVISIBLE (2398 3650);
FORCEADD TAP..1
(2400 3750);
FORCEPROP 3 LASTPIN (2350 3750) SIG_NAME M_B_CPU0_SA_DQS_DN<3>
J 0
(2360 3760);
DISPLAY 0.659574 (2360 3760);
PAINT MONO (2360 3760);
DISPLAY INVISIBLE (2360 3760);
FORCEPROP 1 LASTPIN (2350 3750) BN 3
J 0
(2338 3758);
DISPLAY 0.680851 (2338 3758);
PAINT GREEN (2338 3758);
FORCEPROP 2 LAST CDS_LIB standard
J 0
(2400 3750);
PAINT MONO (2400 3750);
DISPLAY INVISIBLE (2400 3750);
FORCEPROP 1 LAST BODY_TYPE PLUMBING
J 0
(2400 3800);
DISPLAY 0.872340 (2400 3800);
PAINT GREEN (2400 3800);
DISPLAY INVISIBLE (2400 3800);
FORCEPROP 1 LAST HDL_TAP TRUE
J 0
(2725 3625);
DISPLAY 0.872340 (2725 3625);
DISPLAY INVISIBLE (2725 3625);
FORCEPROP 1 LAST PATH I154
J 0
(2398 3750);
DISPLAY 0.872340 (2398 3750);
PAINT GREEN (2398 3750);
DISPLAY INVISIBLE (2398 3750);
FORCEADD TAP..1
(2225 3900);
FORCEPROP 3 LASTPIN (2175 3900) SIG_NAME M_B_CPU0_SA_DQS_DP<4>
J 0
(2185 3910);
DISPLAY 0.659574 (2185 3910);
PAINT MONO (2185 3910);
DISPLAY INVISIBLE (2185 3910);
FORCEPROP 1 LASTPIN (2175 3900) BN 4
J 0
(2163 3908);
DISPLAY 0.680851 (2163 3908);
PAINT GREEN (2163 3908);
FORCEPROP 2 LAST CDS_LIB standard
J 0
(2225 3900);
PAINT MONO (2225 3900);
DISPLAY INVISIBLE (2225 3900);
FORCEPROP 1 LAST BODY_TYPE PLUMBING
J 0
(2225 3950);
DISPLAY 0.872340 (2225 3950);
PAINT GREEN (2225 3950);
DISPLAY INVISIBLE (2225 3950);
FORCEPROP 1 LAST HDL_TAP TRUE
J 0
(2550 3775);
DISPLAY 0.872340 (2550 3775);
DISPLAY INVISIBLE (2550 3775);
FORCEPROP 1 LAST PATH I155
J 0
(2223 3900);
DISPLAY 0.872340 (2223 3900);
PAINT GREEN (2223 3900);
DISPLAY INVISIBLE (2223 3900);
FORCEADD TAP..1
(2225 3800);
FORCEPROP 3 LASTPIN (2175 3800) SIG_NAME M_B_CPU0_SA_DQS_DP<3>
J 0
(2185 3810);
DISPLAY 0.659574 (2185 3810);
PAINT MONO (2185 3810);
DISPLAY INVISIBLE (2185 3810);
FORCEPROP 1 LASTPIN (2175 3800) BN 3
J 0
(2163 3808);
DISPLAY 0.680851 (2163 3808);
PAINT GREEN (2163 3808);
FORCEPROP 2 LAST CDS_LIB standard
J 0
(2225 3800);
PAINT MONO (2225 3800);
DISPLAY INVISIBLE (2225 3800);
FORCEPROP 1 LAST BODY_TYPE PLUMBING
J 0
(2225 3850);
DISPLAY 0.872340 (2225 3850);
PAINT GREEN (2225 3850);
DISPLAY INVISIBLE (2225 3850);
FORCEPROP 1 LAST HDL_TAP TRUE
J 0
(2550 3675);
DISPLAY 0.872340 (2550 3675);
DISPLAY INVISIBLE (2550 3675);
FORCEPROP 1 LAST PATH I156
J 0
(2223 3800);
DISPLAY 0.872340 (2223 3800);
PAINT GREEN (2223 3800);
DISPLAY INVISIBLE (2223 3800);
FORCEADD TAP..1
(2225 4000);
FORCEPROP 3 LASTPIN (2175 4000) SIG_NAME M_B_CPU0_SA_DQS_DP<5>
J 0
(2185 4010);
DISPLAY 0.659574 (2185 4010);
PAINT MONO (2185 4010);
DISPLAY INVISIBLE (2185 4010);
FORCEPROP 1 LASTPIN (2175 4000) BN 5
J 0
(2163 4008);
DISPLAY 0.680851 (2163 4008);
PAINT GREEN (2163 4008);
FORCEPROP 2 LAST CDS_LIB standard
J 0
(2225 4000);
DISPLAY INVISIBLE (2225 4000);
FORCEPROP 1 LAST BODY_TYPE PLUMBING
J 0
(2225 4050);
DISPLAY 0.872340 (2225 4050);
PAINT GREEN (2225 4050);
DISPLAY INVISIBLE (2225 4050);
FORCEPROP 1 LAST HDL_TAP TRUE
J 0
(2550 3875);
DISPLAY 0.872340 (2550 3875);
DISPLAY INVISIBLE (2550 3875);
FORCEPROP 1 LAST PATH I157
J 0
(2223 4000);
DISPLAY 0.872340 (2223 4000);
PAINT GREEN (2223 4000);
DISPLAY INVISIBLE (2223 4000);
FORCEADD TAP..1
(2400 3850);
FORCEPROP 3 LASTPIN (2350 3850) SIG_NAME M_B_CPU0_SA_DQS_DN<4>
J 0
(2360 3860);
DISPLAY 0.659574 (2360 3860);
PAINT MONO (2360 3860);
DISPLAY INVISIBLE (2360 3860);
FORCEPROP 1 LASTPIN (2350 3850) BN 4
J 0
(2338 3858);
DISPLAY 0.680851 (2338 3858);
PAINT GREEN (2338 3858);
FORCEPROP 2 LAST CDS_LIB standard
J 0
(2400 3850);
PAINT MONO (2400 3850);
DISPLAY INVISIBLE (2400 3850);
FORCEPROP 1 LAST BODY_TYPE PLUMBING
J 0
(2400 3900);
DISPLAY 0.872340 (2400 3900);
PAINT GREEN (2400 3900);
DISPLAY INVISIBLE (2400 3900);
FORCEPROP 1 LAST HDL_TAP TRUE
J 0
(2725 3725);
DISPLAY 0.872340 (2725 3725);
DISPLAY INVISIBLE (2725 3725);
FORCEPROP 1 LAST PATH I158
J 0
(2398 3850);
DISPLAY 0.872340 (2398 3850);
PAINT GREEN (2398 3850);
DISPLAY INVISIBLE (2398 3850);
FORCEADD TAP..1
(2400 3950);
FORCEPROP 3 LASTPIN (2350 3950) SIG_NAME M_B_CPU0_SA_DQS_DN<5>
J 0
(2360 3960);
DISPLAY 0.659574 (2360 3960);
PAINT MONO (2360 3960);
DISPLAY INVISIBLE (2360 3960);
FORCEPROP 1 LASTPIN (2350 3950) BN 5
J 0
(2338 3958);
DISPLAY 0.680851 (2338 3958);
PAINT GREEN (2338 3958);
FORCEPROP 2 LAST CDS_LIB standard
J 0
(2400 3950);
DISPLAY INVISIBLE (2400 3950);
FORCEPROP 1 LAST BODY_TYPE PLUMBING
J 0
(2400 4000);
DISPLAY 0.872340 (2400 4000);
PAINT GREEN (2400 4000);
DISPLAY INVISIBLE (2400 4000);
FORCEPROP 1 LAST HDL_TAP TRUE
J 0
(2725 3825);
DISPLAY 0.872340 (2725 3825);
DISPLAY INVISIBLE (2725 3825);
FORCEPROP 1 LAST PATH I159
J 0
(2398 3950);
DISPLAY 0.872340 (2398 3950);
PAINT GREEN (2398 3950);
DISPLAY INVISIBLE (2398 3950);
FORCEADD OFFPAGE..1
(-3100 3250);
FORCEPROP 2 LAST $XR0 21 
J 0
(-3321 3250);
DISPLAY 0.638298 (-3321 3250);
PAINT MONO (-3321 3250);
FORCEPROP 2 LAST CDS_LIB standard
J 0
(-3100 3250);
PAINT MONO (-3100 3250);
DISPLAY INVISIBLE (-3100 3250);
FORCEPROP 1 LAST OFFPAGE TRUE
J 0
(-2775 3125);
DISPLAY 0.872340 (-2775 3125);
DISPLAY INVISIBLE (-2775 3125);
FORCEPROP 1 LAST COMMENT_BODY TRUE
J 0
(-2975 3150);
DISPLAY 0.872340 (-2975 3150);
PAINT GREEN (-2975 3150);
DISPLAY INVISIBLE (-2975 3150);
FORCEPROP 2 LAST PATH I16
J 0
(-3050 3325);
DISPLAY 1.021277 (-3050 3325);
DISPLAY INVISIBLE (-3050 3325);
FORCEADD TAP..1
(2225 4100);
FORCEPROP 3 LASTPIN (2175 4100) SIG_NAME M_B_CPU0_SA_DQS_DP<6>
J 0
(2185 4110);
DISPLAY 0.659574 (2185 4110);
PAINT MONO (2185 4110);
DISPLAY INVISIBLE (2185 4110);
FORCEPROP 1 LASTPIN (2175 4100) BN 6
J 0
(2163 4108);
DISPLAY 0.680851 (2163 4108);
PAINT GREEN (2163 4108);
FORCEPROP 2 LAST CDS_LIB standard
J 0
(2225 4100);
DISPLAY INVISIBLE (2225 4100);
FORCEPROP 1 LAST BODY_TYPE PLUMBING
J 0
(2225 4150);
DISPLAY 0.872340 (2225 4150);
PAINT GREEN (2225 4150);
DISPLAY INVISIBLE (2225 4150);
FORCEPROP 1 LAST HDL_TAP TRUE
J 0
(2550 3975);
DISPLAY 0.872340 (2550 3975);
DISPLAY INVISIBLE (2550 3975);
FORCEPROP 1 LAST PATH I160
J 0
(2223 4100);
DISPLAY 0.872340 (2223 4100);
PAINT GREEN (2223 4100);
DISPLAY INVISIBLE (2223 4100);
FORCEADD TAP..1
(2225 4200);
FORCEPROP 3 LASTPIN (2175 4200) SIG_NAME M_B_CPU0_SA_DQS_DP<7>
J 0
(2185 4210);
DISPLAY 0.659574 (2185 4210);
PAINT MONO (2185 4210);
DISPLAY INVISIBLE (2185 4210);
FORCEPROP 1 LASTPIN (2175 4200) BN 7
J 0
(2163 4208);
DISPLAY 0.680851 (2163 4208);
PAINT GREEN (2163 4208);
FORCEPROP 2 LAST CDS_LIB standard
J 0
(2225 4200);
DISPLAY INVISIBLE (2225 4200);
FORCEPROP 1 LAST BODY_TYPE PLUMBING
J 0
(2225 4250);
DISPLAY 0.872340 (2225 4250);
PAINT GREEN (2225 4250);
DISPLAY INVISIBLE (2225 4250);
FORCEPROP 1 LAST HDL_TAP TRUE
J 0
(2550 4075);
DISPLAY 0.872340 (2550 4075);
DISPLAY INVISIBLE (2550 4075);
FORCEPROP 1 LAST PATH I161
J 0
(2223 4200);
DISPLAY 0.872340 (2223 4200);
PAINT GREEN (2223 4200);
DISPLAY INVISIBLE (2223 4200);
FORCEADD TAP..1
(2400 4050);
FORCEPROP 3 LASTPIN (2350 4050) SIG_NAME M_B_CPU0_SA_DQS_DN<6>
J 0
(2360 4060);
DISPLAY 0.659574 (2360 4060);
PAINT MONO (2360 4060);
DISPLAY INVISIBLE (2360 4060);
FORCEPROP 1 LASTPIN (2350 4050) BN 6
J 0
(2338 4058);
DISPLAY 0.680851 (2338 4058);
PAINT GREEN (2338 4058);
FORCEPROP 2 LAST CDS_LIB standard
J 0
(2400 4050);
DISPLAY INVISIBLE (2400 4050);
FORCEPROP 1 LAST BODY_TYPE PLUMBING
J 0
(2400 4100);
DISPLAY 0.872340 (2400 4100);
PAINT GREEN (2400 4100);
DISPLAY INVISIBLE (2400 4100);
FORCEPROP 1 LAST HDL_TAP TRUE
J 0
(2725 3925);
DISPLAY 0.872340 (2725 3925);
DISPLAY INVISIBLE (2725 3925);
FORCEPROP 1 LAST PATH I162
J 0
(2398 4050);
DISPLAY 0.872340 (2398 4050);
PAINT GREEN (2398 4050);
DISPLAY INVISIBLE (2398 4050);
FORCEADD TAP..1
(2400 4150);
FORCEPROP 3 LASTPIN (2350 4150) SIG_NAME M_B_CPU0_SA_DQS_DN<7>
J 0
(2360 4160);
DISPLAY 0.659574 (2360 4160);
PAINT MONO (2360 4160);
DISPLAY INVISIBLE (2360 4160);
FORCEPROP 1 LASTPIN (2350 4150) BN 7
J 0
(2338 4158);
DISPLAY 0.680851 (2338 4158);
PAINT GREEN (2338 4158);
FORCEPROP 2 LAST CDS_LIB standard
J 0
(2400 4150);
DISPLAY INVISIBLE (2400 4150);
FORCEPROP 1 LAST BODY_TYPE PLUMBING
J 0
(2400 4200);
DISPLAY 0.872340 (2400 4200);
PAINT GREEN (2400 4200);
DISPLAY INVISIBLE (2400 4200);
FORCEPROP 1 LAST HDL_TAP TRUE
J 0
(2725 4025);
DISPLAY 0.872340 (2725 4025);
DISPLAY INVISIBLE (2725 4025);
FORCEPROP 1 LAST PATH I163
J 0
(2398 4150);
DISPLAY 0.872340 (2398 4150);
PAINT GREEN (2398 4150);
DISPLAY INVISIBLE (2398 4150);
FORCEADD TAP..1
(2400 4250);
FORCEPROP 3 LASTPIN (2350 4250) SIG_NAME M_B_CPU0_SA_DQS_DN<8>
J 0
(2360 4260);
DISPLAY 0.659574 (2360 4260);
PAINT MONO (2360 4260);
DISPLAY INVISIBLE (2360 4260);
FORCEPROP 1 LASTPIN (2350 4250) BN 8
J 0
(2338 4258);
DISPLAY 0.680851 (2338 4258);
PAINT GREEN (2338 4258);
FORCEPROP 2 LAST CDS_LIB standard
J 0
(2400 4250);
DISPLAY INVISIBLE (2400 4250);
FORCEPROP 1 LAST BODY_TYPE PLUMBING
J 0
(2400 4300);
DISPLAY 0.872340 (2400 4300);
PAINT GREEN (2400 4300);
DISPLAY INVISIBLE (2400 4300);
FORCEPROP 1 LAST HDL_TAP TRUE
J 0
(2725 4125);
DISPLAY 0.872340 (2725 4125);
DISPLAY INVISIBLE (2725 4125);
FORCEPROP 1 LAST PATH I164
J 0
(2398 4250);
DISPLAY 0.872340 (2398 4250);
PAINT GREEN (2398 4250);
DISPLAY INVISIBLE (2398 4250);
FORCEADD OFFPAGE..2
(3350 3325);
FORCEPROP 2 LAST $XR1 84 
J 0
(3629 3325);
DISPLAY 0.638298 (3629 3325);
PAINT MONO (3629 3325);
FORCEPROP 2 LAST $XR0 21 
J 0
(3539 3325);
DISPLAY 0.638298 (3539 3325);
PAINT MONO (3539 3325);
FORCEPROP 2 LAST CDS_LIB standard
J 0
(3350 3325);
PAINT MONO (3350 3325);
DISPLAY INVISIBLE (3350 3325);
FORCEPROP 1 LAST OFFPAGE TRUE
J 0
(3675 3200);
DISPLAY 1.170213 (3675 3200);
PAINT GREEN (3675 3200);
DISPLAY INVISIBLE (3675 3200);
FORCEPROP 1 LAST COMMENT_BODY TRUE
J 0
(3305 3230);
DISPLAY 1.170213 (3305 3230);
PAINT GREEN (3305 3230);
DISPLAY INVISIBLE (3305 3230);
FORCEPROP 2 LAST PATH I165
J 0
(3525 3400);
DISPLAY 1.021277 (3525 3400);
DISPLAY INVISIBLE (3525 3400);
FORCEADD OFFPAGE..2
(3350 3375);
FORCEPROP 2 LAST $XR1 84 
J 0
(3629 3375);
DISPLAY 0.638298 (3629 3375);
PAINT MONO (3629 3375);
FORCEPROP 2 LAST $XR0 21 
J 0
(3539 3375);
DISPLAY 0.638298 (3539 3375);
PAINT MONO (3539 3375);
FORCEPROP 2 LAST CDS_LIB standard
J 0
(3350 3375);
PAINT MONO (3350 3375);
DISPLAY INVISIBLE (3350 3375);
FORCEPROP 1 LAST OFFPAGE TRUE
J 0
(3675 3250);
DISPLAY 1.170213 (3675 3250);
PAINT GREEN (3675 3250);
DISPLAY INVISIBLE (3675 3250);
FORCEPROP 1 LAST COMMENT_BODY TRUE
J 0
(3305 3280);
DISPLAY 1.170213 (3305 3280);
PAINT GREEN (3305 3280);
DISPLAY INVISIBLE (3305 3280);
FORCEPROP 2 LAST PATH I166
J 0
(3525 3450);
DISPLAY 1.021277 (3525 3450);
DISPLAY INVISIBLE (3525 3450);
FORCEADD OFFPAGE..3
(300 4425);
FORCEPROP 2 LAST $XR1 84 
J 0
(604 4425);
DISPLAY 0.638298 (604 4425);
PAINT MONO (604 4425);
FORCEPROP 2 LAST $XR0 21 
J 0
(514 4425);
DISPLAY 0.638298 (514 4425);
PAINT MONO (514 4425);
FORCEPROP 2 LAST CDS_LIB standard
J 2
(300 4425);
DISPLAY INVISIBLE (300 4425);
FORCEPROP 1 LAST OFFPAGE TRUE
J 0
(625 4300);
DISPLAY 0.872340 (625 4300);
DISPLAY INVISIBLE (625 4300);
FORCEPROP 1 LAST COMMENT_BODY TRUE
J 0
(250 4325);
DISPLAY 0.872340 (250 4325);
PAINT GREEN (250 4325);
DISPLAY INVISIBLE (250 4325);
FORCEPROP 2 LAST PATH I167
J 0
(500 4500);
DISPLAY 1.021277 (500 4500);
DISPLAY INVISIBLE (500 4500);
FORCEADD TAP..1
(2225 4400);
FORCEPROP 3 LASTPIN (2175 4400) SIG_NAME M_B_CPU0_SA_DQS_DP<9>
J 0
(2185 4410);
DISPLAY 0.659574 (2185 4410);
PAINT MONO (2185 4410);
DISPLAY INVISIBLE (2185 4410);
FORCEPROP 1 LASTPIN (2175 4400) BN 9
J 0
(2163 4408);
DISPLAY 0.680851 (2163 4408);
PAINT GREEN (2163 4408);
FORCEPROP 2 LAST CDS_LIB standard
J 0
(2225 4400);
DISPLAY INVISIBLE (2225 4400);
FORCEPROP 1 LAST BODY_TYPE PLUMBING
J 0
(2225 4450);
DISPLAY 0.872340 (2225 4450);
PAINT GREEN (2225 4450);
DISPLAY INVISIBLE (2225 4450);
FORCEPROP 1 LAST HDL_TAP TRUE
J 0
(2550 4275);
DISPLAY 0.872340 (2550 4275);
DISPLAY INVISIBLE (2550 4275);
FORCEPROP 1 LAST PATH I168
J 0
(2223 4400);
DISPLAY 0.872340 (2223 4400);
PAINT GREEN (2223 4400);
DISPLAY INVISIBLE (2223 4400);
FORCEADD TAP..1
(2225 4300);
FORCEPROP 3 LASTPIN (2175 4300) SIG_NAME M_B_CPU0_SA_DQS_DP<8>
J 0
(2185 4310);
DISPLAY 0.659574 (2185 4310);
PAINT MONO (2185 4310);
DISPLAY INVISIBLE (2185 4310);
FORCEPROP 1 LASTPIN (2175 4300) BN 8
J 0
(2163 4308);
DISPLAY 0.680851 (2163 4308);
PAINT GREEN (2163 4308);
FORCEPROP 2 LAST CDS_LIB standard
J 0
(2225 4300);
DISPLAY INVISIBLE (2225 4300);
FORCEPROP 1 LAST BODY_TYPE PLUMBING
J 0
(2225 4350);
DISPLAY 0.872340 (2225 4350);
PAINT GREEN (2225 4350);
DISPLAY INVISIBLE (2225 4350);
FORCEPROP 1 LAST HDL_TAP TRUE
J 0
(2550 4175);
DISPLAY 0.872340 (2550 4175);
DISPLAY INVISIBLE (2550 4175);
FORCEPROP 1 LAST PATH I169
J 0
(2223 4300);
DISPLAY 0.872340 (2223 4300);
PAINT GREEN (2223 4300);
DISPLAY INVISIBLE (2223 4300);
FORCEADD OFFPAGE..1
(-3100 3300);
FORCEPROP 2 LAST $XR0 21 
J 0
(-3321 3300);
DISPLAY 0.638298 (-3321 3300);
PAINT MONO (-3321 3300);
FORCEPROP 2 LAST CDS_LIB standard
J 0
(-3100 3300);
PAINT MONO (-3100 3300);
DISPLAY INVISIBLE (-3100 3300);
FORCEPROP 1 LAST OFFPAGE TRUE
J 0
(-2775 3175);
DISPLAY 0.872340 (-2775 3175);
DISPLAY INVISIBLE (-2775 3175);
FORCEPROP 1 LAST COMMENT_BODY TRUE
J 0
(-2975 3200);
DISPLAY 0.872340 (-2975 3200);
PAINT GREEN (-2975 3200);
DISPLAY INVISIBLE (-2975 3200);
FORCEPROP 2 LAST PATH I17
J 0
(-3050 3375);
DISPLAY 1.021277 (-3050 3375);
DISPLAY INVISIBLE (-3050 3375);
FORCEADD TAP..1
(2400 4350);
FORCEPROP 3 LASTPIN (2350 4350) SIG_NAME M_B_CPU0_SA_DQS_DN<9>
J 0
(2360 4360);
DISPLAY 0.659574 (2360 4360);
PAINT MONO (2360 4360);
DISPLAY INVISIBLE (2360 4360);
FORCEPROP 1 LASTPIN (2350 4350) BN 9
J 0
(2338 4358);
DISPLAY 0.680851 (2338 4358);
PAINT GREEN (2338 4358);
FORCEPROP 2 LAST CDS_LIB standard
J 0
(2400 4350);
DISPLAY INVISIBLE (2400 4350);
FORCEPROP 1 LAST BODY_TYPE PLUMBING
J 0
(2400 4400);
DISPLAY 0.872340 (2400 4400);
PAINT GREEN (2400 4400);
DISPLAY INVISIBLE (2400 4400);
FORCEPROP 1 LAST HDL_TAP TRUE
J 0
(2725 4225);
DISPLAY 0.872340 (2725 4225);
DISPLAY INVISIBLE (2725 4225);
FORCEPROP 1 LAST PATH I170
J 0
(2398 4350);
DISPLAY 0.872340 (2398 4350);
PAINT GREEN (2398 4350);
DISPLAY INVISIBLE (2398 4350);
FORCEADD OFFPAGE..2
(3350 4375);
FORCEPROP 2 LAST $XR1 84 
J 0
(3629 4375);
DISPLAY 0.638298 (3629 4375);
PAINT MONO (3629 4375);
FORCEPROP 2 LAST $XR0 21 
J 0
(3539 4375);
DISPLAY 0.638298 (3539 4375);
PAINT MONO (3539 4375);
FORCEPROP 2 LAST CDS_LIB standard
J 0
(3350 4375);
PAINT MONO (3350 4375);
DISPLAY INVISIBLE (3350 4375);
FORCEPROP 1 LAST OFFPAGE TRUE
J 0
(3675 4250);
DISPLAY 1.170213 (3675 4250);
PAINT GREEN (3675 4250);
DISPLAY INVISIBLE (3675 4250);
FORCEPROP 1 LAST COMMENT_BODY TRUE
J 0
(3305 4280);
DISPLAY 1.170213 (3305 4280);
PAINT GREEN (3305 4280);
DISPLAY INVISIBLE (3305 4280);
FORCEPROP 2 LAST PATH I171
J 0
(3525 4450);
DISPLAY 1.021277 (3525 4450);
DISPLAY INVISIBLE (3525 4450);
FORCEADD OFFPAGE..2
(3350 4425);
FORCEPROP 2 LAST $XR1 84 
J 0
(3629 4425);
DISPLAY 0.638298 (3629 4425);
PAINT MONO (3629 4425);
FORCEPROP 2 LAST $XR0 21 
J 0
(3539 4425);
DISPLAY 0.638298 (3539 4425);
PAINT MONO (3539 4425);
FORCEPROP 2 LAST CDS_LIB standard
J 0
(3350 4425);
PAINT MONO (3350 4425);
DISPLAY INVISIBLE (3350 4425);
FORCEPROP 1 LAST OFFPAGE TRUE
J 0
(3675 4300);
DISPLAY 1.170213 (3675 4300);
PAINT GREEN (3675 4300);
DISPLAY INVISIBLE (3675 4300);
FORCEPROP 1 LAST COMMENT_BODY TRUE
J 0
(3305 4330);
DISPLAY 1.170213 (3305 4330);
PAINT GREEN (3305 4330);
DISPLAY INVISIBLE (3305 4330);
FORCEPROP 2 LAST PATH I172
J 0
(3525 4500);
DISPLAY 1.021277 (3525 4500);
DISPLAY INVISIBLE (3525 4500);
FORCEADD UNIVERSAL_GND..1
(3900 700);
FORCEPROP 3 LASTPIN (3900 750) SIG_NAME GND\g
J 0
(3910 760);
DISPLAY 0.659574 (3910 760);
PAINT MONO (3910 760);
DISPLAY INVISIBLE (3910 760);
FORCEPROP 2 LAST CDS_LIB logical_power
J 0
(3900 700);
PAINT MONO (3900 700);
DISPLAY INVISIBLE (3900 700);
FORCEPROP 1 LAST HDL_POWER GND
J 1
(3925 625);
DISPLAY 0.872340 (3925 625);
PAINT GREEN (3925 625);
DISPLAY INVISIBLE (3925 625);
FORCEPROP 1 LAST PATH I173
J 0
(3975 700);
DISPLAY 0.872340 (3975 700);
PAINT AQUA (3975 700);
DISPLAY INVISIBLE (3975 700);
FORCEADD SCONN288_ADR50017P087CC..3
(4750 2775);
FORCEPROP 1 LAST PART_NUMBER DFHST8FS460
J 0
(4295 4699);
DISPLAY 0.723404 (4295 4699);
PAINT GREEN (4295 4699);
DISPLAY INVISIBLE (4295 4699);
FORCEPROP 1 LAST MATERIAL IO
J 0
(4295 4572);
DISPLAY 0.723404 (4295 4572);
PAINT GREEN (4295 4572);
FORCEPROP 2 LAST PART_TYPE SMLF
J 0
(4300 4850);
DISPLAY 1.021277 (4300 4850);
FORCEPROP 2 LAST VALUE SCONN288_ADR50017-P087CC
J 0
(4300 4800);
DISPLAY 1.021277 (4300 4800);
FORCEPROP 1 LAST $LOCATION J4
J 0
(4300 4750);
DISPLAY 0.723404 (4300 4750);
PAINT GREEN (4300 4750);
FORCEPROP 0 LASTPIN (5350 1150) $PN G1
J 0
(5360 1160);
DISPLAY 0.680851 (5360 1160);
PAINT MONO (5360 1160);
FORCEPROP 0 LASTPIN (5350 1100) $PN G2
J 0
(5360 1110);
DISPLAY 0.680851 (5360 1110);
PAINT MONO (5360 1110);
FORCEPROP 0 LASTPIN (5350 1050) $PN G3
J 0
(5360 1060);
DISPLAY 0.680851 (5360 1060);
PAINT MONO (5360 1060);
FORCEPROP 0 LASTPIN (4150 4300) $PN 1
J 2
(4140 4310);
DISPLAY 0.680851 (4140 4310);
PAINT MONO (4140 4310);
FORCEPROP 0 LASTPIN (4150 4350) $PN 145
J 2
(4140 4360);
DISPLAY 0.680851 (4140 4360);
PAINT MONO (4140 4360);
FORCEPROP 0 LASTPIN (4150 4400) $PN 146
J 2
(4140 4410);
DISPLAY 0.680851 (4140 4410);
PAINT MONO (4140 4410);
FORCEPROP 0 LASTPIN (5350 1250) $PN 6
J 0
(5360 1260);
DISPLAY 0.680851 (5360 1260);
PAINT MONO (5360 1260);
FORCEPROP 0 LASTPIN (5350 1300) $PN 8
J 0
(5360 1310);
DISPLAY 0.680851 (5360 1310);
PAINT MONO (5360 1310);
FORCEPROP 0 LASTPIN (5350 1350) $PN 10
J 0
(5360 1360);
DISPLAY 0.680851 (5360 1360);
PAINT MONO (5360 1360);
FORCEPROP 0 LASTPIN (5350 1400) $PN 13
J 0
(5360 1410);
DISPLAY 0.680851 (5360 1410);
PAINT MONO (5360 1410);
FORCEPROP 0 LASTPIN (5350 1450) $PN 15
J 0
(5360 1460);
DISPLAY 0.680851 (5360 1460);
PAINT MONO (5360 1460);
FORCEPROP 0 LASTPIN (5350 1500) $PN 17
J 0
(5360 1510);
DISPLAY 0.680851 (5360 1510);
PAINT MONO (5360 1510);
FORCEPROP 0 LASTPIN (5350 1550) $PN 19
J 0
(5360 1560);
DISPLAY 0.680851 (5360 1560);
PAINT MONO (5360 1560);
FORCEPROP 0 LASTPIN (5350 1600) $PN 21
J 0
(5360 1610);
DISPLAY 0.680851 (5360 1610);
PAINT MONO (5360 1610);
FORCEPROP 0 LASTPIN (5350 1650) $PN 24
J 0
(5360 1660);
DISPLAY 0.680851 (5360 1660);
PAINT MONO (5360 1660);
FORCEPROP 0 LASTPIN (5350 1700) $PN 26
J 0
(5360 1710);
DISPLAY 0.680851 (5360 1710);
PAINT MONO (5360 1710);
FORCEPROP 0 LASTPIN (5350 1750) $PN 28
J 0
(5360 1760);
DISPLAY 0.680851 (5360 1760);
PAINT MONO (5360 1760);
FORCEPROP 0 LASTPIN (5350 1800) $PN 30
J 0
(5360 1810);
DISPLAY 0.680851 (5360 1810);
PAINT MONO (5360 1810);
FORCEPROP 0 LASTPIN (5350 1850) $PN 32
J 0
(5360 1860);
DISPLAY 0.680851 (5360 1860);
PAINT MONO (5360 1860);
FORCEPROP 0 LASTPIN (5350 1900) $PN 35
J 0
(5360 1910);
DISPLAY 0.680851 (5360 1910);
PAINT MONO (5360 1910);
FORCEPROP 0 LASTPIN (5350 1950) $PN 37
J 0
(5360 1960);
DISPLAY 0.680851 (5360 1960);
PAINT MONO (5360 1960);
FORCEPROP 0 LASTPIN (5350 2000) $PN 39
J 0
(5360 2010);
DISPLAY 0.680851 (5360 2010);
PAINT MONO (5360 2010);
FORCEPROP 0 LASTPIN (5350 2050) $PN 41
J 0
(5360 2060);
DISPLAY 0.680851 (5360 2060);
PAINT MONO (5360 2060);
FORCEPROP 0 LASTPIN (5350 2100) $PN 43
J 0
(5360 2110);
DISPLAY 0.680851 (5360 2110);
PAINT MONO (5360 2110);
FORCEPROP 0 LASTPIN (5350 2150) $PN 46
J 0
(5360 2160);
DISPLAY 0.680851 (5360 2160);
PAINT MONO (5360 2160);
FORCEPROP 0 LASTPIN (5350 2200) $PN 48
J 0
(5360 2210);
DISPLAY 0.680851 (5360 2210);
PAINT MONO (5360 2210);
FORCEPROP 0 LASTPIN (5350 2250) $PN 50
J 0
(5360 2260);
DISPLAY 0.680851 (5360 2260);
PAINT MONO (5360 2260);
FORCEPROP 0 LASTPIN (5350 2300) $PN 52
J 0
(5360 2310);
DISPLAY 0.680851 (5360 2310);
PAINT MONO (5360 2310);
FORCEPROP 0 LASTPIN (5350 2350) $PN 54
J 0
(5360 2360);
DISPLAY 0.680851 (5360 2360);
PAINT MONO (5360 2360);
FORCEPROP 0 LASTPIN (5350 2400) $PN 57
J 0
(5360 2410);
DISPLAY 0.680851 (5360 2410);
PAINT MONO (5360 2410);
FORCEPROP 0 LASTPIN (5350 2450) $PN 59
J 0
(5360 2460);
DISPLAY 0.680851 (5360 2460);
PAINT MONO (5360 2460);
FORCEPROP 0 LASTPIN (5350 2500) $PN 61
J 0
(5360 2510);
DISPLAY 0.680851 (5360 2510);
PAINT MONO (5360 2510);
FORCEPROP 0 LASTPIN (5350 2550) $PN 63
J 0
(5360 2560);
DISPLAY 0.680851 (5360 2560);
PAINT MONO (5360 2560);
FORCEPROP 0 LASTPIN (5350 2600) $PN 65
J 0
(5360 2610);
DISPLAY 0.680851 (5360 2610);
PAINT MONO (5360 2610);
FORCEPROP 0 LASTPIN (5350 2650) $PN 67
J 0
(5360 2660);
DISPLAY 0.680851 (5360 2660);
PAINT MONO (5360 2660);
FORCEPROP 0 LASTPIN (5350 2700) $PN 69
J 0
(5360 2710);
DISPLAY 0.680851 (5360 2710);
PAINT MONO (5360 2710);
FORCEPROP 0 LASTPIN (5350 2750) $PN 71
J 0
(5360 2760);
DISPLAY 0.680851 (5360 2760);
PAINT MONO (5360 2760);
FORCEPROP 0 LASTPIN (5350 2800) $PN 73
J 0
(5360 2810);
DISPLAY 0.680851 (5360 2810);
PAINT MONO (5360 2810);
FORCEPROP 0 LASTPIN (5350 2850) $PN 75
J 0
(5360 2860);
DISPLAY 0.680851 (5360 2860);
PAINT MONO (5360 2860);
FORCEPROP 0 LASTPIN (5350 2900) $PN 77
J 0
(5360 2910);
DISPLAY 0.680851 (5360 2910);
PAINT MONO (5360 2910);
FORCEPROP 0 LASTPIN (5350 2950) $PN 79
J 0
(5360 2960);
DISPLAY 0.680851 (5360 2960);
PAINT MONO (5360 2960);
FORCEPROP 0 LASTPIN (5350 3000) $PN 81
J 0
(5360 3010);
DISPLAY 0.680851 (5360 3010);
PAINT MONO (5360 3010);
FORCEPROP 0 LASTPIN (5350 3050) $PN 83
J 0
(5360 3060);
DISPLAY 0.680851 (5360 3060);
PAINT MONO (5360 3060);
FORCEPROP 0 LASTPIN (5350 3100) $PN 85
J 0
(5360 3110);
DISPLAY 0.680851 (5360 3110);
PAINT MONO (5360 3110);
FORCEPROP 0 LASTPIN (5350 3150) $PN 88
J 0
(5360 3160);
DISPLAY 0.680851 (5360 3160);
PAINT MONO (5360 3160);
FORCEPROP 0 LASTPIN (5350 3200) $PN 90
J 0
(5360 3210);
DISPLAY 0.680851 (5360 3210);
PAINT MONO (5360 3210);
FORCEPROP 0 LASTPIN (5350 3250) $PN 92
J 0
(5360 3260);
DISPLAY 0.680851 (5360 3260);
PAINT MONO (5360 3260);
FORCEPROP 0 LASTPIN (5350 3300) $PN 95
J 0
(5360 3310);
DISPLAY 0.680851 (5360 3310);
PAINT MONO (5360 3310);
FORCEPROP 0 LASTPIN (5350 3350) $PN 97
J 0
(5360 3360);
DISPLAY 0.680851 (5360 3360);
PAINT MONO (5360 3360);
FORCEPROP 0 LASTPIN (5350 3400) $PN 99
J 0
(5360 3410);
DISPLAY 0.680851 (5360 3410);
PAINT MONO (5360 3410);
FORCEPROP 0 LASTPIN (5350 3450) $PN 101
J 0
(5360 3460);
DISPLAY 0.680851 (5360 3460);
PAINT MONO (5360 3460);
FORCEPROP 0 LASTPIN (5350 3500) $PN 103
J 0
(5360 3510);
DISPLAY 0.680851 (5360 3510);
PAINT MONO (5360 3510);
FORCEPROP 0 LASTPIN (5350 3550) $PN 106
J 0
(5360 3560);
DISPLAY 0.680851 (5360 3560);
PAINT MONO (5360 3560);
FORCEPROP 0 LASTPIN (5350 3600) $PN 108
J 0
(5360 3610);
DISPLAY 0.680851 (5360 3610);
PAINT MONO (5360 3610);
FORCEPROP 0 LASTPIN (5350 3650) $PN 110
J 0
(5360 3660);
DISPLAY 0.680851 (5360 3660);
PAINT MONO (5360 3660);
FORCEPROP 0 LASTPIN (5350 3700) $PN 112
J 0
(5360 3710);
DISPLAY 0.680851 (5360 3710);
PAINT MONO (5360 3710);
FORCEPROP 0 LASTPIN (5350 3750) $PN 114
J 0
(5360 3760);
DISPLAY 0.680851 (5360 3760);
PAINT MONO (5360 3760);
FORCEPROP 0 LASTPIN (5350 3800) $PN 117
J 0
(5360 3810);
DISPLAY 0.680851 (5360 3810);
PAINT MONO (5360 3810);
FORCEPROP 0 LASTPIN (5350 3850) $PN 119
J 0
(5360 3860);
DISPLAY 0.680851 (5360 3860);
PAINT MONO (5360 3860);
FORCEPROP 0 LASTPIN (5350 3900) $PN 121
J 0
(5360 3910);
DISPLAY 0.680851 (5360 3910);
PAINT MONO (5360 3910);
FORCEPROP 0 LASTPIN (5350 3950) $PN 123
J 0
(5360 3960);
DISPLAY 0.680851 (5360 3960);
PAINT MONO (5360 3960);
FORCEPROP 0 LASTPIN (5350 4000) $PN 125
J 0
(5360 4010);
DISPLAY 0.680851 (5360 4010);
PAINT MONO (5360 4010);
FORCEPROP 0 LASTPIN (5350 4050) $PN 128
J 0
(5360 4060);
DISPLAY 0.680851 (5360 4060);
PAINT MONO (5360 4060);
FORCEPROP 0 LASTPIN (5350 4100) $PN 130
J 0
(5360 4110);
DISPLAY 0.680851 (5360 4110);
PAINT MONO (5360 4110);
FORCEPROP 0 LASTPIN (5350 4150) $PN 132
J 0
(5360 4160);
DISPLAY 0.680851 (5360 4160);
PAINT MONO (5360 4160);
FORCEPROP 0 LASTPIN (5350 4200) $PN 134
J 0
(5360 4210);
DISPLAY 0.680851 (5360 4210);
PAINT MONO (5360 4210);
FORCEPROP 0 LASTPIN (5350 4250) $PN 136
J 0
(5360 4260);
DISPLAY 0.680851 (5360 4260);
PAINT MONO (5360 4260);
FORCEPROP 0 LASTPIN (5350 4300) $PN 139
J 0
(5360 4310);
DISPLAY 0.680851 (5360 4310);
PAINT MONO (5360 4310);
FORCEPROP 0 LASTPIN (5350 4350) $PN 141
J 0
(5360 4360);
DISPLAY 0.680851 (5360 4360);
PAINT MONO (5360 4360);
FORCEPROP 0 LASTPIN (5350 4400) $PN 143
J 0
(5360 4410);
DISPLAY 0.680851 (5360 4410);
PAINT MONO (5360 4410);
FORCEPROP 0 LASTPIN (4150 1150) $PN 151
J 2
(4140 1160);
DISPLAY 0.680851 (4140 1160);
PAINT MONO (4140 1160);
FORCEPROP 0 LASTPIN (4150 1200) $PN 153
J 2
(4140 1210);
DISPLAY 0.680851 (4140 1210);
PAINT MONO (4140 1210);
FORCEPROP 0 LASTPIN (4150 1250) $PN 155
J 2
(4140 1260);
DISPLAY 0.680851 (4140 1260);
PAINT MONO (4140 1260);
FORCEPROP 0 LASTPIN (4150 1300) $PN 158
J 2
(4140 1310);
DISPLAY 0.680851 (4140 1310);
PAINT MONO (4140 1310);
FORCEPROP 0 LASTPIN (4150 1350) $PN 160
J 2
(4140 1360);
DISPLAY 0.680851 (4140 1360);
PAINT MONO (4140 1360);
FORCEPROP 0 LASTPIN (4150 1400) $PN 162
J 2
(4140 1410);
DISPLAY 0.680851 (4140 1410);
PAINT MONO (4140 1410);
FORCEPROP 0 LASTPIN (4150 1450) $PN 164
J 2
(4140 1460);
DISPLAY 0.680851 (4140 1460);
PAINT MONO (4140 1460);
FORCEPROP 0 LASTPIN (4150 1500) $PN 166
J 2
(4140 1510);
DISPLAY 0.680851 (4140 1510);
PAINT MONO (4140 1510);
FORCEPROP 0 LASTPIN (4150 1550) $PN 169
J 2
(4140 1560);
DISPLAY 0.680851 (4140 1560);
PAINT MONO (4140 1560);
FORCEPROP 0 LASTPIN (4150 1600) $PN 171
J 2
(4140 1610);
DISPLAY 0.680851 (4140 1610);
PAINT MONO (4140 1610);
FORCEPROP 0 LASTPIN (4150 1650) $PN 173
J 2
(4140 1660);
DISPLAY 0.680851 (4140 1660);
PAINT MONO (4140 1660);
FORCEPROP 0 LASTPIN (4150 1700) $PN 175
J 2
(4140 1710);
DISPLAY 0.680851 (4140 1710);
PAINT MONO (4140 1710);
FORCEPROP 0 LASTPIN (4150 1750) $PN 177
J 2
(4140 1760);
DISPLAY 0.680851 (4140 1760);
PAINT MONO (4140 1760);
FORCEPROP 0 LASTPIN (4150 1800) $PN 180
J 2
(4140 1810);
DISPLAY 0.680851 (4140 1810);
PAINT MONO (4140 1810);
FORCEPROP 0 LASTPIN (4150 1850) $PN 182
J 2
(4140 1860);
DISPLAY 0.680851 (4140 1860);
PAINT MONO (4140 1860);
FORCEPROP 0 LASTPIN (4150 1900) $PN 184
J 2
(4140 1910);
DISPLAY 0.680851 (4140 1910);
PAINT MONO (4140 1910);
FORCEPROP 0 LASTPIN (4150 1950) $PN 186
J 2
(4140 1960);
DISPLAY 0.680851 (4140 1960);
PAINT MONO (4140 1960);
FORCEPROP 0 LASTPIN (4150 2000) $PN 188
J 2
(4140 2010);
DISPLAY 0.680851 (4140 2010);
PAINT MONO (4140 2010);
FORCEPROP 0 LASTPIN (4150 2050) $PN 191
J 2
(4140 2060);
DISPLAY 0.680851 (4140 2060);
PAINT MONO (4140 2060);
FORCEPROP 0 LASTPIN (4150 2100) $PN 193
J 2
(4140 2110);
DISPLAY 0.680851 (4140 2110);
PAINT MONO (4140 2110);
FORCEPROP 0 LASTPIN (4150 2150) $PN 195
J 2
(4140 2160);
DISPLAY 0.680851 (4140 2160);
PAINT MONO (4140 2160);
FORCEPROP 0 LASTPIN (4150 2200) $PN 197
J 2
(4140 2210);
DISPLAY 0.680851 (4140 2210);
PAINT MONO (4140 2210);
FORCEPROP 0 LASTPIN (4150 2250) $PN 199
J 2
(4140 2260);
DISPLAY 0.680851 (4140 2260);
PAINT MONO (4140 2260);
FORCEPROP 0 LASTPIN (4150 2300) $PN 202
J 2
(4140 2310);
DISPLAY 0.680851 (4140 2310);
PAINT MONO (4140 2310);
FORCEPROP 0 LASTPIN (4150 2350) $PN 204
J 2
(4140 2360);
DISPLAY 0.680851 (4140 2360);
PAINT MONO (4140 2360);
FORCEPROP 0 LASTPIN (4150 2400) $PN 206
J 2
(4140 2410);
DISPLAY 0.680851 (4140 2410);
PAINT MONO (4140 2410);
FORCEPROP 0 LASTPIN (4150 2450) $PN 208
J 2
(4140 2460);
DISPLAY 0.680851 (4140 2460);
PAINT MONO (4140 2460);
FORCEPROP 0 LASTPIN (4150 2500) $PN 210
J 2
(4140 2510);
DISPLAY 0.680851 (4140 2510);
PAINT MONO (4140 2510);
FORCEPROP 0 LASTPIN (4150 2550) $PN 212
J 2
(4140 2560);
DISPLAY 0.680851 (4140 2560);
PAINT MONO (4140 2560);
FORCEPROP 0 LASTPIN (4150 2600) $PN 214
J 2
(4140 2610);
DISPLAY 0.680851 (4140 2610);
PAINT MONO (4140 2610);
FORCEPROP 0 LASTPIN (4150 2650) $PN 216
J 2
(4140 2660);
DISPLAY 0.680851 (4140 2660);
PAINT MONO (4140 2660);
FORCEPROP 0 LASTPIN (4150 2700) $PN 219
J 2
(4140 2710);
DISPLAY 0.680851 (4140 2710);
PAINT MONO (4140 2710);
FORCEPROP 0 LASTPIN (4150 2750) $PN 222
J 2
(4140 2760);
DISPLAY 0.680851 (4140 2760);
PAINT MONO (4140 2760);
FORCEPROP 0 LASTPIN (4150 2800) $PN 224
J 2
(4140 2810);
DISPLAY 0.680851 (4140 2810);
PAINT MONO (4140 2810);
FORCEPROP 0 LASTPIN (4150 2850) $PN 226
J 2
(4140 2860);
DISPLAY 0.680851 (4140 2860);
PAINT MONO (4140 2860);
FORCEPROP 0 LASTPIN (4150 2900) $PN 228
J 2
(4140 2910);
DISPLAY 0.680851 (4140 2910);
PAINT MONO (4140 2910);
FORCEPROP 0 LASTPIN (4150 2950) $PN 230
J 2
(4140 2960);
DISPLAY 0.680851 (4140 2960);
PAINT MONO (4140 2960);
FORCEPROP 0 LASTPIN (4150 3000) $PN 233
J 2
(4140 3010);
DISPLAY 0.680851 (4140 3010);
PAINT MONO (4140 3010);
FORCEPROP 0 LASTPIN (4150 3050) $PN 235
J 2
(4140 3060);
DISPLAY 0.680851 (4140 3060);
PAINT MONO (4140 3060);
FORCEPROP 0 LASTPIN (4150 3100) $PN 237
J 2
(4140 3110);
DISPLAY 0.680851 (4140 3110);
PAINT MONO (4140 3110);
FORCEPROP 0 LASTPIN (4150 3150) $PN 240
J 2
(4140 3160);
DISPLAY 0.680851 (4140 3160);
PAINT MONO (4140 3160);
FORCEPROP 0 LASTPIN (4150 3200) $PN 242
J 2
(4140 3210);
DISPLAY 0.680851 (4140 3210);
PAINT MONO (4140 3210);
FORCEPROP 0 LASTPIN (4150 3250) $PN 244
J 2
(4140 3260);
DISPLAY 0.680851 (4140 3260);
PAINT MONO (4140 3260);
FORCEPROP 0 LASTPIN (4150 3300) $PN 246
J 2
(4140 3310);
DISPLAY 0.680851 (4140 3310);
PAINT MONO (4140 3310);
FORCEPROP 0 LASTPIN (4150 3350) $PN 248
J 2
(4140 3360);
DISPLAY 0.680851 (4140 3360);
PAINT MONO (4140 3360);
FORCEPROP 0 LASTPIN (4150 3400) $PN 251
J 2
(4140 3410);
DISPLAY 0.680851 (4140 3410);
PAINT MONO (4140 3410);
FORCEPROP 0 LASTPIN (4150 3450) $PN 253
J 2
(4140 3460);
DISPLAY 0.680851 (4140 3460);
PAINT MONO (4140 3460);
FORCEPROP 0 LASTPIN (4150 3500) $PN 255
J 2
(4140 3510);
DISPLAY 0.680851 (4140 3510);
PAINT MONO (4140 3510);
FORCEPROP 0 LASTPIN (4150 3550) $PN 257
J 2
(4140 3560);
DISPLAY 0.680851 (4140 3560);
PAINT MONO (4140 3560);
FORCEPROP 0 LASTPIN (4150 3600) $PN 259
J 2
(4140 3610);
DISPLAY 0.680851 (4140 3610);
PAINT MONO (4140 3610);
FORCEPROP 0 LASTPIN (4150 3650) $PN 262
J 2
(4140 3660);
DISPLAY 0.680851 (4140 3660);
PAINT MONO (4140 3660);
FORCEPROP 0 LASTPIN (4150 3700) $PN 264
J 2
(4140 3710);
DISPLAY 0.680851 (4140 3710);
PAINT MONO (4140 3710);
FORCEPROP 0 LASTPIN (4150 3750) $PN 266
J 2
(4140 3760);
DISPLAY 0.680851 (4140 3760);
PAINT MONO (4140 3760);
FORCEPROP 0 LASTPIN (4150 3800) $PN 268
J 2
(4140 3810);
DISPLAY 0.680851 (4140 3810);
PAINT MONO (4140 3810);
FORCEPROP 0 LASTPIN (4150 3850) $PN 270
J 2
(4140 3860);
DISPLAY 0.680851 (4140 3860);
PAINT MONO (4140 3860);
FORCEPROP 0 LASTPIN (4150 3900) $PN 273
J 2
(4140 3910);
DISPLAY 0.680851 (4140 3910);
PAINT MONO (4140 3910);
FORCEPROP 0 LASTPIN (4150 3950) $PN 275
J 2
(4140 3960);
DISPLAY 0.680851 (4140 3960);
PAINT MONO (4140 3960);
FORCEPROP 0 LASTPIN (4150 4000) $PN 277
J 2
(4140 4010);
DISPLAY 0.680851 (4140 4010);
PAINT MONO (4140 4010);
FORCEPROP 0 LASTPIN (4150 4050) $PN 279
J 2
(4140 4060);
DISPLAY 0.680851 (4140 4060);
PAINT MONO (4140 4060);
FORCEPROP 0 LASTPIN (4150 4100) $PN 281
J 2
(4140 4110);
DISPLAY 0.680851 (4140 4110);
PAINT MONO (4140 4110);
FORCEPROP 0 LASTPIN (4150 4150) $PN 284
J 2
(4140 4160);
DISPLAY 0.680851 (4140 4160);
PAINT MONO (4140 4160);
FORCEPROP 0 LASTPIN (4150 4200) $PN 286
J 2
(4140 4210);
DISPLAY 0.680851 (4140 4210);
PAINT MONO (4140 4210);
FORCEPROP 0 LASTPIN (4150 4250) $PN 288
J 2
(4140 4260);
DISPLAY 0.680851 (4140 4260);
PAINT MONO (4140 4260);
FORCEPROP 2 LAST CDS_LIB pure_quanta
J 0
(4750 2775);
DISPLAY INVISIBLE (4750 2775);
FORCEPROP 1 LAST CDS_LMAN_SYM_OUTLINE -450,1775,450,-1775
J 0
(4750 2775);
DISPLAY 0.468085 (4750 2775);
PAINT GREEN (4750 2775);
DISPLAY INVISIBLE (4750 2775);
FORCEPROP 1 LAST NEEDS_NO_SIZE TRUE
J 0
(4750 2775);
DISPLAY 0.723404 (4750 2775);
PAINT GREEN (4750 2775);
DISPLAY INVISIBLE (4750 2775);
FORCEPROP 2 LAST CDS_LOCATION J4
J 0
(4300 4900);
DISPLAY 1.021277 (4300 4900);
DISPLAY INVISIBLE (4300 4900);
FORCEPROP 0 LAST $SEC 3
J 0
(4300 4900);
DISPLAY 0.680851 (4300 4900);
PAINT MONO (4300 4900);
DISPLAY INVISIBLE (4300 4900);
FORCEPROP 2 LAST CDS_SEC 3
J 0
(4300 4900);
DISPLAY 1.021277 (4300 4900);
DISPLAY INVISIBLE (4300 4900);
FORCEPROP 1 LAST PATH I174
J 0
(4750 2775);
DISPLAY 0.723404 (4750 2775);
PAINT GREEN (4750 2775);
DISPLAY INVISIBLE (4750 2775);
FORCEADD UNIVERSAL_GND..1
(5600 700);
FORCEPROP 3 LASTPIN (5600 750) SIG_NAME GND\g
J 0
(5610 760);
DISPLAY 0.659574 (5610 760);
PAINT MONO (5610 760);
DISPLAY INVISIBLE (5610 760);
FORCEPROP 2 LAST CDS_LIB logical_power
J 0
(5600 700);
PAINT MONO (5600 700);
DISPLAY INVISIBLE (5600 700);
FORCEPROP 1 LAST HDL_POWER GND
J 1
(5625 625);
DISPLAY 0.872340 (5625 625);
PAINT GREEN (5625 625);
DISPLAY INVISIBLE (5625 625);
FORCEPROP 1 LAST PATH I175
J 0
(5675 700);
DISPLAY 0.872340 (5675 700);
PAINT AQUA (5675 700);
DISPLAY INVISIBLE (5675 700);
FORCEADD VCC_CORE..1
(3900 4950);
FORCEPROP 3 LASTPIN (3900 4900) SIG_NAME P12V_S3_AUX_CPU0_NVDIMM\g
J 0
(3910 4910);
DISPLAY 0.659574 (3910 4910);
PAINT MONO (3910 4910);
DISPLAY INVISIBLE (3910 4910);
FORCEPROP 1 LAST HDL_POWER P12V_S3_AUX_CPU0_NVDIMM
J 1
(3900 5000);
DISPLAY 1.148936 (3900 5000);
PAINT GREEN (3900 5000);
FORCEPROP 2 LAST CDS_LIB logical_power
J 0
(3900 4950);
PAINT MONO (3900 4950);
DISPLAY INVISIBLE (3900 4950);
FORCEPROP 1 LAST PATH I176
J 0
(3950 4975);
DISPLAY 0.872340 (3950 4975);
PAINT AQUA (3950 4975);
DISPLAY INVISIBLE (3950 4975);
FORCEADD OFFPAGE..3
R 2
(-3100 1550);
FORCEPROP 2 LAST $XR0 114 
J 0
(-3380 1550);
DISPLAY 0.638298 (-3380 1550);
PAINT MONO (-3380 1550);
FORCEPROP 2 LAST CDS_LIB standard
J 0
(-3100 1550);
PAINT MONO (-3100 1550);
DISPLAY INVISIBLE (-3100 1550);
FORCEPROP 1 LAST OFFPAGE TRUE
J 2
(-3425 1425);
DISPLAY 0.872340 (-3425 1425);
DISPLAY INVISIBLE (-3425 1425);
FORCEPROP 1 LAST COMMENT_BODY TRUE
J 2
(-3050 1450);
DISPLAY 0.872340 (-3050 1450);
PAINT GREEN (-3050 1450);
DISPLAY INVISIBLE (-3050 1450);
FORCEPROP 2 LAST PATH I177
J 0
(-3050 1625);
DISPLAY 1.021277 (-3050 1625);
DISPLAY INVISIBLE (-3050 1625);
FORCEADD SCONN288_ADR50017P087CC..2
(1325 3400);
FORCEPROP 1 LAST PART_NUMBER DFHST8FS460
J 0
(720 4688);
DISPLAY 0.723404 (720 4688);
PAINT GREEN (720 4688);
DISPLAY INVISIBLE (720 4688);
FORCEPROP 2 LAST PART_TYPE SMLF
J 0
(725 4925);
DISPLAY 1.021277 (725 4925);
FORCEPROP 2 LAST VALUE SCONN288_ADR50017-P087CC
J 0
(725 4875);
DISPLAY 1.021277 (725 4875);
FORCEPROP 1 LAST MATERIAL IO
J 0
(720 4561);
DISPLAY 0.723404 (720 4561);
PAINT GREEN (720 4561);
FORCEPROP 1 LAST LOCATION J4
J 0
(720 4835);
DISPLAY 0.723404 (720 4835);
PAINT GREEN (720 4835);
FORCEPROP 0 LASTPIN (2075 3450) $PN 12
J 0
(2085 3460);
DISPLAY 0.680851 (2085 3460);
PAINT MONO (2085 3460);
FORCEPROP 0 LASTPIN (2075 3500) $PN 11
J 0
(2085 3510);
DISPLAY 0.680851 (2085 3510);
PAINT MONO (2085 3510);
FORCEPROP 0 LASTPIN (2075 2400) $PN 105
J 0
(2085 2410);
DISPLAY 0.680851 (2085 2410);
PAINT MONO (2085 2410);
FORCEPROP 0 LASTPIN (2075 2450) $PN 104
J 0
(2085 2460);
DISPLAY 0.680851 (2085 2460);
PAINT MONO (2085 2460);
FORCEPROP 0 LASTPIN (2075 3550) $PN 23
J 0
(2085 3560);
DISPLAY 0.680851 (2085 3560);
PAINT MONO (2085 3560);
FORCEPROP 0 LASTPIN (2075 3600) $PN 22
J 0
(2085 3610);
DISPLAY 0.680851 (2085 3610);
PAINT MONO (2085 3610);
FORCEPROP 0 LASTPIN (2075 2500) $PN 116
J 0
(2085 2510);
DISPLAY 0.680851 (2085 2510);
PAINT MONO (2085 2510);
FORCEPROP 0 LASTPIN (2075 2550) $PN 115
J 0
(2085 2560);
DISPLAY 0.680851 (2085 2560);
PAINT MONO (2085 2560);
FORCEPROP 0 LASTPIN (2075 3650) $PN 34
J 0
(2085 3660);
DISPLAY 0.680851 (2085 3660);
PAINT MONO (2085 3660);
FORCEPROP 0 LASTPIN (2075 3700) $PN 33
J 0
(2085 3710);
DISPLAY 0.680851 (2085 3710);
PAINT MONO (2085 3710);
FORCEPROP 0 LASTPIN (2075 2600) $PN 127
J 0
(2085 2610);
DISPLAY 0.680851 (2085 2610);
PAINT MONO (2085 2610);
FORCEPROP 0 LASTPIN (2075 2650) $PN 126
J 0
(2085 2660);
DISPLAY 0.680851 (2085 2660);
PAINT MONO (2085 2660);
FORCEPROP 0 LASTPIN (2075 3750) $PN 45
J 0
(2085 3760);
DISPLAY 0.680851 (2085 3760);
PAINT MONO (2085 3760);
FORCEPROP 0 LASTPIN (2075 3800) $PN 44
J 0
(2085 3810);
DISPLAY 0.680851 (2085 3810);
PAINT MONO (2085 3810);
FORCEPROP 0 LASTPIN (2075 2700) $PN 138
J 0
(2085 2710);
DISPLAY 0.680851 (2085 2710);
PAINT MONO (2085 2710);
FORCEPROP 0 LASTPIN (2075 2750) $PN 137
J 0
(2085 2760);
DISPLAY 0.680851 (2085 2760);
PAINT MONO (2085 2760);
FORCEPROP 0 LASTPIN (2075 3850) $PN 56
J 0
(2085 3860);
DISPLAY 0.680851 (2085 3860);
PAINT MONO (2085 3860);
FORCEPROP 0 LASTPIN (2075 3900) $PN 55
J 0
(2085 3910);
DISPLAY 0.680851 (2085 3910);
PAINT MONO (2085 3910);
FORCEPROP 0 LASTPIN (2075 2800) $PN 238
J 0
(2085 2810);
DISPLAY 0.680851 (2085 2810);
PAINT MONO (2085 2810);
FORCEPROP 0 LASTPIN (2075 2850) $PN 239
J 0
(2085 2860);
DISPLAY 0.680851 (2085 2860);
PAINT MONO (2085 2860);
FORCEPROP 0 LASTPIN (2075 3950) $PN 156
J 0
(2085 3960);
DISPLAY 0.680851 (2085 3960);
PAINT MONO (2085 3960);
FORCEPROP 0 LASTPIN (2075 4000) $PN 157
J 0
(2085 4010);
DISPLAY 0.680851 (2085 4010);
PAINT MONO (2085 4010);
FORCEPROP 0 LASTPIN (2075 2900) $PN 249
J 0
(2085 2910);
DISPLAY 0.680851 (2085 2910);
PAINT MONO (2085 2910);
FORCEPROP 0 LASTPIN (2075 2950) $PN 250
J 0
(2085 2960);
DISPLAY 0.680851 (2085 2960);
PAINT MONO (2085 2960);
FORCEPROP 0 LASTPIN (2075 4050) $PN 167
J 0
(2085 4060);
DISPLAY 0.680851 (2085 4060);
PAINT MONO (2085 4060);
FORCEPROP 0 LASTPIN (2075 4100) $PN 168
J 0
(2085 4110);
DISPLAY 0.680851 (2085 4110);
PAINT MONO (2085 4110);
FORCEPROP 0 LASTPIN (2075 3000) $PN 260
J 0
(2085 3010);
DISPLAY 0.680851 (2085 3010);
PAINT MONO (2085 3010);
FORCEPROP 0 LASTPIN (2075 3050) $PN 261
J 0
(2085 3060);
DISPLAY 0.680851 (2085 3060);
PAINT MONO (2085 3060);
FORCEPROP 0 LASTPIN (2075 4150) $PN 178
J 0
(2085 4160);
DISPLAY 0.680851 (2085 4160);
PAINT MONO (2085 4160);
FORCEPROP 0 LASTPIN (2075 4200) $PN 179
J 0
(2085 4210);
DISPLAY 0.680851 (2085 4210);
PAINT MONO (2085 4210);
FORCEPROP 0 LASTPIN (2075 3100) $PN 271
J 0
(2085 3110);
DISPLAY 0.680851 (2085 3110);
PAINT MONO (2085 3110);
FORCEPROP 0 LASTPIN (2075 3150) $PN 272
J 0
(2085 3160);
DISPLAY 0.680851 (2085 3160);
PAINT MONO (2085 3160);
FORCEPROP 0 LASTPIN (2075 4250) $PN 189
J 0
(2085 4260);
DISPLAY 0.680851 (2085 4260);
PAINT MONO (2085 4260);
FORCEPROP 0 LASTPIN (2075 4300) $PN 190
J 0
(2085 4310);
DISPLAY 0.680851 (2085 4310);
PAINT MONO (2085 4310);
FORCEPROP 0 LASTPIN (2075 3200) $PN 282
J 0
(2085 3210);
DISPLAY 0.680851 (2085 3210);
PAINT MONO (2085 3210);
FORCEPROP 0 LASTPIN (2075 3250) $PN 283
J 0
(2085 3260);
DISPLAY 0.680851 (2085 3260);
PAINT MONO (2085 3260);
FORCEPROP 0 LASTPIN (2075 4350) $PN 200
J 0
(2085 4360);
DISPLAY 0.680851 (2085 4360);
PAINT MONO (2085 4360);
FORCEPROP 0 LASTPIN (2075 4400) $PN 201
J 0
(2085 4410);
DISPLAY 0.680851 (2085 4410);
PAINT MONO (2085 4410);
FORCEPROP 0 LASTPIN (2075 3300) $PN 94
J 0
(2085 3310);
DISPLAY 0.680851 (2085 3310);
PAINT MONO (2085 3310);
FORCEPROP 0 LASTPIN (2075 3350) $PN 93
J 0
(2085 3360);
DISPLAY 0.680851 (2085 3360);
PAINT MONO (2085 3360);
FORCEPROP 1 LAST NEEDS_NO_SIZE TRUE
J 0
(1325 3400);
DISPLAY 0.723404 (1325 3400);
PAINT GREEN (1325 3400);
DISPLAY INVISIBLE (1325 3400);
FORCEPROP 1 LAST CDS_LMAN_SYM_OUTLINE -600,1150,600,-1150
J 0
(1325 3400);
DISPLAY 0.468085 (1325 3400);
PAINT GREEN (1325 3400);
DISPLAY INVISIBLE (1325 3400);
FORCEPROP 2 LAST CDS_LIB pure_quanta
J 0
(1325 3400);
DISPLAY INVISIBLE (1325 3400);
FORCEPROP 0 LAST $SEC 2
J 0
(725 4975);
DISPLAY 0.680851 (725 4975);
PAINT MONO (725 4975);
DISPLAY INVISIBLE (725 4975);
FORCEPROP 0 LAST CDS_SEC 2
J 0
(725 4975);
DISPLAY 1.021277 (725 4975);
DISPLAY INVISIBLE (725 4975);
FORCEPROP 1 LAST PATH I178
J 0
(1325 3400);
DISPLAY 0.723404 (1325 3400);
PAINT GREEN (1325 3400);
DISPLAY INVISIBLE (1325 3400);
FORCEADD OFFPAGE..1
(-2025 1625);
FORCEPROP 2 LAST $XR7 89 
J 0
(-2937 1625);
DISPLAY 0.638298 (-2937 1625);
PAINT MONO (-2937 1625);
FORCEPROP 2 LAST $XR6 88 
J 0
(-2847 1625);
DISPLAY 0.638298 (-2847 1625);
PAINT MONO (-2847 1625);
FORCEPROP 2 LAST $XR5 87 
J 0
(-2757 1625);
DISPLAY 0.638298 (-2757 1625);
PAINT MONO (-2757 1625);
FORCEPROP 2 LAST $XR4 86 
J 0
(-2667 1625);
DISPLAY 0.638298 (-2667 1625);
PAINT MONO (-2667 1625);
FORCEPROP 2 LAST $XR3 84 
J 0
(-2577 1625);
DISPLAY 0.638298 (-2577 1625);
PAINT MONO (-2577 1625);
FORCEPROP 2 LAST $XR2 83 
J 0
(-2487 1625);
DISPLAY 0.638298 (-2487 1625);
PAINT MONO (-2487 1625);
FORCEPROP 2 LAST $XR1 82 
J 0
(-2397 1625);
DISPLAY 0.638298 (-2397 1625);
PAINT MONO (-2397 1625);
FORCEPROP 2 LAST $XR0 229 
J 0
(-2307 1625);
DISPLAY 0.638298 (-2307 1625);
PAINT MONO (-2307 1625);
FORCEPROP 2 LAST CDS_LIB standard
J 0
(-2025 1625);
PAINT MONO (-2025 1625);
DISPLAY INVISIBLE (-2025 1625);
FORCEPROP 1 LAST OFFPAGE TRUE
J 0
(-1700 1500);
DISPLAY 0.872340 (-1700 1500);
DISPLAY INVISIBLE (-1700 1500);
FORCEPROP 1 LAST COMMENT_BODY TRUE
J 0
(-1900 1525);
DISPLAY 0.872340 (-1900 1525);
PAINT GREEN (-1900 1525);
DISPLAY INVISIBLE (-1900 1525);
FORCEPROP 2 LAST PATH I179
J 2
(-2475 1675);
DISPLAY 1.021277 (-2475 1675);
DISPLAY INVISIBLE (-2475 1675);
FORCEADD OFFPAGE..1
(-3100 3400);
FORCEPROP 2 LAST $XR0 21 
J 0
(-3321 3400);
DISPLAY 0.638298 (-3321 3400);
PAINT MONO (-3321 3400);
FORCEPROP 2 LAST CDS_LIB standard
J 0
(-3100 3400);
PAINT MONO (-3100 3400);
DISPLAY INVISIBLE (-3100 3400);
FORCEPROP 1 LAST OFFPAGE TRUE
J 0
(-2775 3275);
DISPLAY 0.872340 (-2775 3275);
DISPLAY INVISIBLE (-2775 3275);
FORCEPROP 1 LAST COMMENT_BODY TRUE
J 0
(-2975 3300);
DISPLAY 0.872340 (-2975 3300);
PAINT GREEN (-2975 3300);
DISPLAY INVISIBLE (-2975 3300);
FORCEPROP 2 LAST PATH I18
J 0
(-3050 3475);
DISPLAY 1.021277 (-3050 3475);
DISPLAY INVISIBLE (-3050 3475);
FORCEADD Q_RES..1
(-3275 1700);
FORCEPROP 1 LAST PART_NUMBER CS04992FB07
J 0
(-3175 1675);
DISPLAY 0.404255 (-3175 1675);
DISPLAY INVISIBLE (-3175 1675);
FORCEPROP 1 LAST VALUE 49.9
J 2
(-3050 1700);
DISPLAY 0.510638 (-3050 1700);
FORCEPROP 1 LAST MATERIAL CHIP
J 0
(-3425 1650);
DISPLAY 0.404255 (-3425 1650);
FORCEPROP 1 LAST $LOCATION R3878
J 0
(-3475 1700);
DISPLAY 0.638298 (-3475 1700);
FORCEPROP 1 LASTPIN (-3375 1700) $PN 1
J 0
(-3363 1712);
DISPLAY 0.787234 (-3363 1712);
PAINT MONO (-3363 1712);
FORCEPROP 1 LASTPIN (-3175 1700) $PN 2
J 0
(-3213 1712);
DISPLAY 0.787234 (-3213 1712);
PAINT MONO (-3213 1712);
FORCEPROP 2 LAST CDS_LIB pure_quanta
J 0
(-3275 1700);
DISPLAY INVISIBLE (-3275 1700);
FORCEPROP 1 LAST PACK_TYPE 0402LF
J 0
(-2975 1700);
DISPLAY 0.510638 (-2975 1700);
DISPLAY INVISIBLE (-2975 1700);
FORCEPROP 1 LAST TOLERANCE 1%
J 0
(-3050 1700);
DISPLAY 0.510638 (-3050 1700);
DISPLAY INVISIBLE (-3050 1700);
FORCEPROP 1 LAST WATTAGE 1/16W
J 2
(-2975 1650);
DISPLAY 0.404255 (-2975 1650);
DISPLAY INVISIBLE (-2975 1650);
FORCEPROP 0 LAST CDS_LOCATION R3878
J 0
(-3400 1750);
DISPLAY 1.021277 (-3400 1750);
DISPLAY INVISIBLE (-3400 1750);
FORCEPROP 0 LAST $SEC 1
J 0
(-3400 1750);
DISPLAY 0.680851 (-3400 1750);
PAINT MONO (-3400 1750);
DISPLAY INVISIBLE (-3400 1750);
FORCEPROP 0 LAST CDS_SEC 1
J 0
(-3400 1750);
DISPLAY 1.021277 (-3400 1750);
DISPLAY INVISIBLE (-3400 1750);
FORCEPROP 1 LAST PATH I180
J 0
(-3325 1850);
DISPLAY 0.978723 (-3325 1850);
PAINT WHITE (-3325 1850);
DISPLAY INVISIBLE (-3325 1850);
FORCEADD OFFPAGE..1
(-3100 3450);
FORCEPROP 2 LAST $XR0 21 
J 0
(-3321 3450);
DISPLAY 0.638298 (-3321 3450);
PAINT MONO (-3321 3450);
FORCEPROP 2 LAST CDS_LIB standard
J 0
(-3100 3450);
PAINT MONO (-3100 3450);
DISPLAY INVISIBLE (-3100 3450);
FORCEPROP 1 LAST OFFPAGE TRUE
J 0
(-2775 3325);
DISPLAY 0.872340 (-2775 3325);
DISPLAY INVISIBLE (-2775 3325);
FORCEPROP 1 LAST COMMENT_BODY TRUE
J 0
(-2975 3350);
DISPLAY 0.872340 (-2975 3350);
PAINT GREEN (-2975 3350);
DISPLAY INVISIBLE (-2975 3350);
FORCEPROP 2 LAST PATH I19
J 0
(-3050 3525);
DISPLAY 1.021277 (-3050 3525);
DISPLAY INVISIBLE (-3050 3525);
FORCEADD UNIVERSAL_GND..1
(-1950 25);
FORCEPROP 3 LASTPIN (-1950 75) SIG_NAME GND\g
J 0
(-1940 85);
DISPLAY 0.659574 (-1940 85);
PAINT MONO (-1940 85);
DISPLAY INVISIBLE (-1940 85);
FORCEPROP 2 LAST CDS_LIB logical_power
J 0
(-1950 25);
PAINT MONO (-1950 25);
DISPLAY INVISIBLE (-1950 25);
FORCEPROP 1 LAST HDL_POWER GND
J 1
(-1925 -50);
DISPLAY 0.872340 (-1925 -50);
PAINT GREEN (-1925 -50);
DISPLAY INVISIBLE (-1925 -50);
FORCEPROP 1 LAST PATH I2
J 0
(-1875 25);
DISPLAY 0.872340 (-1875 25);
PAINT AQUA (-1875 25);
DISPLAY INVISIBLE (-1875 25);
FORCEADD OFFPAGE..1
(-3100 3550);
FORCEPROP 2 LAST $XR1 84 
J 0
(-3411 3550);
DISPLAY 0.638298 (-3411 3550);
PAINT MONO (-3411 3550);
FORCEPROP 2 LAST $XR0 21 
J 0
(-3321 3550);
DISPLAY 0.638298 (-3321 3550);
PAINT MONO (-3321 3550);
FORCEPROP 2 LAST CDS_LIB standard
J 0
(-3100 3550);
PAINT MONO (-3100 3550);
DISPLAY INVISIBLE (-3100 3550);
FORCEPROP 1 LAST OFFPAGE TRUE
J 0
(-2775 3425);
DISPLAY 0.872340 (-2775 3425);
DISPLAY INVISIBLE (-2775 3425);
FORCEPROP 1 LAST COMMENT_BODY TRUE
J 0
(-2975 3450);
DISPLAY 0.872340 (-2975 3450);
PAINT GREEN (-2975 3450);
DISPLAY INVISIBLE (-2975 3450);
FORCEPROP 2 LAST PATH I20
J 0
(-3050 3625);
DISPLAY 1.021277 (-3050 3625);
DISPLAY INVISIBLE (-3050 3625);
FORCEADD OFFPAGE..1
(-3100 3600);
FORCEPROP 2 LAST $XR1 84 
J 0
(-3411 3600);
DISPLAY 0.638298 (-3411 3600);
PAINT MONO (-3411 3600);
FORCEPROP 2 LAST $XR0 21 
J 0
(-3321 3600);
DISPLAY 0.638298 (-3321 3600);
PAINT MONO (-3321 3600);
FORCEPROP 2 LAST CDS_LIB standard
J 0
(-3100 3600);
PAINT MONO (-3100 3600);
DISPLAY INVISIBLE (-3100 3600);
FORCEPROP 1 LAST OFFPAGE TRUE
J 0
(-2775 3475);
DISPLAY 0.872340 (-2775 3475);
DISPLAY INVISIBLE (-2775 3475);
FORCEPROP 1 LAST COMMENT_BODY TRUE
J 0
(-2975 3500);
DISPLAY 0.872340 (-2975 3500);
PAINT GREEN (-2975 3500);
DISPLAY INVISIBLE (-2975 3500);
FORCEPROP 2 LAST PATH I21
J 0
(-3050 3675);
DISPLAY 1.021277 (-3050 3675);
DISPLAY INVISIBLE (-3050 3675);
FORCEADD OFFPAGE..1
(-3100 4025);
FORCEPROP 2 LAST $XR1 84 
J 0
(-3411 4025);
DISPLAY 0.638298 (-3411 4025);
PAINT MONO (-3411 4025);
FORCEPROP 2 LAST $XR0 21 
J 0
(-3321 4025);
DISPLAY 0.638298 (-3321 4025);
PAINT MONO (-3321 4025);
FORCEPROP 2 LAST CDS_LIB standard
J 0
(-3100 4025);
PAINT MONO (-3100 4025);
DISPLAY INVISIBLE (-3100 4025);
FORCEPROP 1 LAST OFFPAGE TRUE
J 0
(-2775 3900);
DISPLAY 0.872340 (-2775 3900);
DISPLAY INVISIBLE (-2775 3900);
FORCEPROP 1 LAST COMMENT_BODY TRUE
J 0
(-2975 3925);
DISPLAY 0.872340 (-2975 3925);
PAINT GREEN (-2975 3925);
DISPLAY INVISIBLE (-2975 3925);
FORCEPROP 2 LAST PATH I22
J 0
(-3050 4100);
DISPLAY 1.021277 (-3050 4100);
DISPLAY INVISIBLE (-3050 4100);
FORCEADD SCONN288_ADR50017P087CC..1
(-1350 2675);
FORCEPROP 1 LAST PART_NUMBER DFHST8FS460
J 0
(-1795 4685);
DISPLAY 0.723404 (-1795 4685);
PAINT GREEN (-1795 4685);
DISPLAY INVISIBLE (-1795 4685);
FORCEPROP 1 LAST MATERIAL IO
J 0
(-1795 4558);
DISPLAY 0.723404 (-1795 4558);
PAINT GREEN (-1795 4558);
FORCEPROP 2 LAST PART_TYPE SMLF
J 0
(-1800 4850);
DISPLAY 1.021277 (-1800 4850);
FORCEPROP 2 LAST VALUE SCONN288_ADR50017-P087CC
J 0
(-1800 4800);
DISPLAY 1.021277 (-1800 4800);
FORCEPROP 1 LAST $LOCATION J4
J 0
(-1800 4750);
DISPLAY 0.723404 (-1800 4750);
PAINT GREEN (-1800 4750);
FORCEPROP 0 LASTPIN (-1950 2050) $PN 62
J 2
(-1960 2060);
DISPLAY 0.680851 (-1960 2060);
PAINT MONO (-1960 2060);
FORCEPROP 0 LASTPIN (-1950 4100) $PN 66
J 2
(-1960 4110);
DISPLAY 0.680851 (-1960 4110);
PAINT MONO (-1960 4110);
FORCEPROP 0 LASTPIN (-1950 3700) $PN 76
J 2
(-1960 3710);
DISPLAY 0.680851 (-1960 3710);
PAINT MONO (-1960 3710);
FORCEPROP 0 LASTPIN (-1950 4150) $PN 211
J 2
(-1960 4160);
DISPLAY 0.680851 (-1960 4160);
PAINT MONO (-1960 4160);
FORCEPROP 0 LASTPIN (-1950 3750) $PN 221
J 2
(-1960 3760);
DISPLAY 0.680851 (-1960 3760);
PAINT MONO (-1960 3760);
FORCEPROP 0 LASTPIN (-1950 4200) $PN 68
J 2
(-1960 4210);
DISPLAY 0.680851 (-1960 4210);
PAINT MONO (-1960 4210);
FORCEPROP 0 LASTPIN (-1950 3800) $PN 78
J 2
(-1960 3810);
DISPLAY 0.680851 (-1960 3810);
PAINT MONO (-1960 3810);
FORCEPROP 0 LASTPIN (-1950 4250) $PN 213
J 2
(-1960 4260);
DISPLAY 0.680851 (-1960 4260);
PAINT MONO (-1960 4260);
FORCEPROP 0 LASTPIN (-1950 3850) $PN 223
J 2
(-1960 3860);
DISPLAY 0.680851 (-1960 3860);
PAINT MONO (-1960 3860);
FORCEPROP 0 LASTPIN (-1950 4300) $PN 70
J 2
(-1960 4310);
DISPLAY 0.680851 (-1960 4310);
PAINT MONO (-1960 4310);
FORCEPROP 0 LASTPIN (-1950 3900) $PN 80
J 2
(-1960 3910);
DISPLAY 0.680851 (-1960 3910);
PAINT MONO (-1960 3910);
FORCEPROP 0 LASTPIN (-1950 4350) $PN 215
J 2
(-1960 4360);
DISPLAY 0.680851 (-1960 4360);
PAINT MONO (-1960 4360);
FORCEPROP 0 LASTPIN (-1950 3950) $PN 225
J 2
(-1960 3960);
DISPLAY 0.680851 (-1960 3960);
PAINT MONO (-1960 3960);
FORCEPROP 0 LASTPIN (-1950 4400) $PN 72
J 2
(-1960 4410);
DISPLAY 0.680851 (-1960 4410);
PAINT MONO (-1960 4410);
FORCEPROP 0 LASTPIN (-1950 4000) $PN 82
J 2
(-1960 4010);
DISPLAY 0.680851 (-1960 4010);
PAINT MONO (-1960 4010);
FORCEPROP 0 LASTPIN (-1950 2650) $PN 51
J 2
(-1960 2660);
DISPLAY 0.680851 (-1960 2660);
PAINT MONO (-1960 2660);
FORCEPROP 0 LASTPIN (-1950 2200) $PN 96
J 2
(-1960 2210);
DISPLAY 0.680851 (-1960 2210);
PAINT MONO (-1960 2210);
FORCEPROP 0 LASTPIN (-1950 2700) $PN 53
J 2
(-1960 2710);
DISPLAY 0.680851 (-1960 2710);
PAINT MONO (-1960 2710);
FORCEPROP 0 LASTPIN (-1950 2250) $PN 98
J 2
(-1960 2260);
DISPLAY 0.680851 (-1960 2260);
PAINT MONO (-1960 2260);
FORCEPROP 0 LASTPIN (-1950 2750) $PN 196
J 2
(-1960 2760);
DISPLAY 0.680851 (-1960 2760);
PAINT MONO (-1960 2760);
FORCEPROP 0 LASTPIN (-1950 2300) $PN 241
J 2
(-1960 2310);
DISPLAY 0.680851 (-1960 2310);
PAINT MONO (-1960 2310);
FORCEPROP 0 LASTPIN (-1950 2800) $PN 198
J 2
(-1960 2810);
DISPLAY 0.680851 (-1960 2810);
PAINT MONO (-1960 2810);
FORCEPROP 0 LASTPIN (-1950 2350) $PN 243
J 2
(-1960 2360);
DISPLAY 0.680851 (-1960 2360);
PAINT MONO (-1960 2360);
FORCEPROP 0 LASTPIN (-1950 2850) $PN 58
J 2
(-1960 2860);
DISPLAY 0.680851 (-1960 2860);
PAINT MONO (-1960 2860);
FORCEPROP 0 LASTPIN (-1950 2400) $PN 89
J 2
(-1960 2410);
DISPLAY 0.680851 (-1960 2410);
PAINT MONO (-1960 2410);
FORCEPROP 0 LASTPIN (-1950 2900) $PN 60
J 2
(-1960 2910);
DISPLAY 0.680851 (-1960 2910);
PAINT MONO (-1960 2910);
FORCEPROP 0 LASTPIN (-1950 2450) $PN 91
J 2
(-1960 2460);
DISPLAY 0.680851 (-1960 2460);
PAINT MONO (-1960 2460);
FORCEPROP 0 LASTPIN (-1950 2950) $PN 203
J 2
(-1960 2960);
DISPLAY 0.680851 (-1960 2960);
PAINT MONO (-1960 2960);
FORCEPROP 0 LASTPIN (-1950 2500) $PN 234
J 2
(-1960 2510);
DISPLAY 0.680851 (-1960 2510);
PAINT MONO (-1960 2510);
FORCEPROP 0 LASTPIN (-1950 3000) $PN 205
J 2
(-1960 3010);
DISPLAY 0.680851 (-1960 3010);
PAINT MONO (-1960 3010);
FORCEPROP 0 LASTPIN (-1950 2550) $PN 236
J 2
(-1960 2560);
DISPLAY 0.680851 (-1960 2560);
PAINT MONO (-1960 2560);
FORCEPROP 0 LASTPIN (-1950 3100) $PN 218
J 2
(-1960 3110);
DISPLAY 0.680851 (-1960 3110);
PAINT MONO (-1960 3110);
FORCEPROP 0 LASTPIN (-1950 3150) $PN 217
J 2
(-1960 3160);
DISPLAY 0.680851 (-1960 3160);
PAINT MONO (-1960 3160);
FORCEPROP 0 LASTPIN (-1950 3400) $PN 64
J 2
(-1960 3410);
DISPLAY 0.680851 (-1960 3410);
PAINT MONO (-1960 3410);
FORCEPROP 0 LASTPIN (-1950 3250) $PN 84
J 2
(-1960 3260);
DISPLAY 0.680851 (-1960 3260);
PAINT MONO (-1960 3260);
FORCEPROP 0 LASTPIN (-1950 3450) $PN 209
J 2
(-1960 3460);
DISPLAY 0.680851 (-1960 3460);
PAINT MONO (-1960 3460);
FORCEPROP 0 LASTPIN (-1950 3300) $PN 229
J 2
(-1960 3310);
DISPLAY 0.680851 (-1960 3310);
PAINT MONO (-1960 3310);
FORCEPROP 0 LASTPIN (-750 2850) $PN 7
J 0
(-740 2860);
DISPLAY 0.680851 (-740 2860);
PAINT MONO (-740 2860);
FORCEPROP 0 LASTPIN (-750 1200) $PN 100
J 0
(-740 1210);
DISPLAY 0.680851 (-740 1210);
PAINT MONO (-740 1210);
FORCEPROP 0 LASTPIN (-750 2900) $PN 9
J 0
(-740 2910);
DISPLAY 0.680851 (-740 2910);
PAINT MONO (-740 2910);
FORCEPROP 0 LASTPIN (-750 1250) $PN 102
J 0
(-740 1260);
DISPLAY 0.680851 (-740 1260);
PAINT MONO (-740 1260);
FORCEPROP 0 LASTPIN (-750 2950) $PN 152
J 0
(-740 2960);
DISPLAY 0.680851 (-740 2960);
PAINT MONO (-740 2960);
FORCEPROP 0 LASTPIN (-750 1300) $PN 245
J 0
(-740 1310);
DISPLAY 0.680851 (-740 1310);
PAINT MONO (-740 1310);
FORCEPROP 0 LASTPIN (-750 3000) $PN 154
J 0
(-740 3010);
DISPLAY 0.680851 (-740 3010);
PAINT MONO (-740 3010);
FORCEPROP 0 LASTPIN (-750 1350) $PN 247
J 0
(-740 1360);
DISPLAY 0.680851 (-740 1360);
PAINT MONO (-740 1360);
FORCEPROP 0 LASTPIN (-750 3050) $PN 14
J 0
(-740 3060);
DISPLAY 0.680851 (-740 3060);
PAINT MONO (-740 3060);
FORCEPROP 0 LASTPIN (-750 1400) $PN 107
J 0
(-740 1410);
DISPLAY 0.680851 (-740 1410);
PAINT MONO (-740 1410);
FORCEPROP 0 LASTPIN (-750 3100) $PN 16
J 0
(-740 3110);
DISPLAY 0.680851 (-740 3110);
PAINT MONO (-740 3110);
FORCEPROP 0 LASTPIN (-750 1450) $PN 109
J 0
(-740 1460);
DISPLAY 0.680851 (-740 1460);
PAINT MONO (-740 1460);
FORCEPROP 0 LASTPIN (-750 3150) $PN 159
J 0
(-740 3160);
DISPLAY 0.680851 (-740 3160);
PAINT MONO (-740 3160);
FORCEPROP 0 LASTPIN (-750 1500) $PN 252
J 0
(-740 1510);
DISPLAY 0.680851 (-740 1510);
PAINT MONO (-740 1510);
FORCEPROP 0 LASTPIN (-750 3200) $PN 161
J 0
(-740 3210);
DISPLAY 0.680851 (-740 3210);
PAINT MONO (-740 3210);
FORCEPROP 0 LASTPIN (-750 1550) $PN 254
J 0
(-740 1560);
DISPLAY 0.680851 (-740 1560);
PAINT MONO (-740 1560);
FORCEPROP 0 LASTPIN (-750 3250) $PN 18
J 0
(-740 3260);
DISPLAY 0.680851 (-740 3260);
PAINT MONO (-740 3260);
FORCEPROP 0 LASTPIN (-750 1600) $PN 111
J 0
(-740 1610);
DISPLAY 0.680851 (-740 1610);
PAINT MONO (-740 1610);
FORCEPROP 0 LASTPIN (-750 3300) $PN 20
J 0
(-740 3310);
DISPLAY 0.680851 (-740 3310);
PAINT MONO (-740 3310);
FORCEPROP 0 LASTPIN (-750 1650) $PN 113
J 0
(-740 1660);
DISPLAY 0.680851 (-740 1660);
PAINT MONO (-740 1660);
FORCEPROP 0 LASTPIN (-750 3350) $PN 163
J 0
(-740 3360);
DISPLAY 0.680851 (-740 3360);
PAINT MONO (-740 3360);
FORCEPROP 0 LASTPIN (-750 1700) $PN 256
J 0
(-740 1710);
DISPLAY 0.680851 (-740 1710);
PAINT MONO (-740 1710);
FORCEPROP 0 LASTPIN (-750 3400) $PN 165
J 0
(-740 3410);
DISPLAY 0.680851 (-740 3410);
PAINT MONO (-740 3410);
FORCEPROP 0 LASTPIN (-750 1750) $PN 258
J 0
(-740 1760);
DISPLAY 0.680851 (-740 1760);
PAINT MONO (-740 1760);
FORCEPROP 0 LASTPIN (-750 3450) $PN 25
J 0
(-740 3460);
DISPLAY 0.680851 (-740 3460);
PAINT MONO (-740 3460);
FORCEPROP 0 LASTPIN (-750 1800) $PN 118
J 0
(-740 1810);
DISPLAY 0.680851 (-740 1810);
PAINT MONO (-740 1810);
FORCEPROP 0 LASTPIN (-750 3500) $PN 27
J 0
(-740 3510);
DISPLAY 0.680851 (-740 3510);
PAINT MONO (-740 3510);
FORCEPROP 0 LASTPIN (-750 1850) $PN 120
J 0
(-740 1860);
DISPLAY 0.680851 (-740 1860);
PAINT MONO (-740 1860);
FORCEPROP 0 LASTPIN (-750 3550) $PN 170
J 0
(-740 3560);
DISPLAY 0.680851 (-740 3560);
PAINT MONO (-740 3560);
FORCEPROP 0 LASTPIN (-750 1900) $PN 263
J 0
(-740 1910);
DISPLAY 0.680851 (-740 1910);
PAINT MONO (-740 1910);
FORCEPROP 0 LASTPIN (-750 3600) $PN 172
J 0
(-740 3610);
DISPLAY 0.680851 (-740 3610);
PAINT MONO (-740 3610);
FORCEPROP 0 LASTPIN (-750 1950) $PN 265
J 0
(-740 1960);
DISPLAY 0.680851 (-740 1960);
PAINT MONO (-740 1960);
FORCEPROP 0 LASTPIN (-750 3650) $PN 29
J 0
(-740 3660);
DISPLAY 0.680851 (-740 3660);
PAINT MONO (-740 3660);
FORCEPROP 0 LASTPIN (-750 2000) $PN 122
J 0
(-740 2010);
DISPLAY 0.680851 (-740 2010);
PAINT MONO (-740 2010);
FORCEPROP 0 LASTPIN (-750 3700) $PN 31
J 0
(-740 3710);
DISPLAY 0.680851 (-740 3710);
PAINT MONO (-740 3710);
FORCEPROP 0 LASTPIN (-750 2050) $PN 124
J 0
(-740 2060);
DISPLAY 0.680851 (-740 2060);
PAINT MONO (-740 2060);
FORCEPROP 0 LASTPIN (-750 3750) $PN 174
J 0
(-740 3760);
DISPLAY 0.680851 (-740 3760);
PAINT MONO (-740 3760);
FORCEPROP 0 LASTPIN (-750 2100) $PN 267
J 0
(-740 2110);
DISPLAY 0.680851 (-740 2110);
PAINT MONO (-740 2110);
FORCEPROP 0 LASTPIN (-750 3800) $PN 176
J 0
(-740 3810);
DISPLAY 0.680851 (-740 3810);
PAINT MONO (-740 3810);
FORCEPROP 0 LASTPIN (-750 2150) $PN 269
J 0
(-740 2160);
DISPLAY 0.680851 (-740 2160);
PAINT MONO (-740 2160);
FORCEPROP 0 LASTPIN (-750 3850) $PN 36
J 0
(-740 3860);
DISPLAY 0.680851 (-740 3860);
PAINT MONO (-740 3860);
FORCEPROP 0 LASTPIN (-750 2200) $PN 129
J 0
(-740 2210);
DISPLAY 0.680851 (-740 2210);
PAINT MONO (-740 2210);
FORCEPROP 0 LASTPIN (-750 3900) $PN 38
J 0
(-740 3910);
DISPLAY 0.680851 (-740 3910);
PAINT MONO (-740 3910);
FORCEPROP 0 LASTPIN (-750 2250) $PN 131
J 0
(-740 2260);
DISPLAY 0.680851 (-740 2260);
PAINT MONO (-740 2260);
FORCEPROP 0 LASTPIN (-750 3950) $PN 181
J 0
(-740 3960);
DISPLAY 0.680851 (-740 3960);
PAINT MONO (-740 3960);
FORCEPROP 0 LASTPIN (-750 2300) $PN 274
J 0
(-740 2310);
DISPLAY 0.680851 (-740 2310);
PAINT MONO (-740 2310);
FORCEPROP 0 LASTPIN (-750 4000) $PN 183
J 0
(-740 4010);
DISPLAY 0.680851 (-740 4010);
PAINT MONO (-740 4010);
FORCEPROP 0 LASTPIN (-750 2350) $PN 276
J 0
(-740 2360);
DISPLAY 0.680851 (-740 2360);
PAINT MONO (-740 2360);
FORCEPROP 0 LASTPIN (-750 4050) $PN 40
J 0
(-740 4060);
DISPLAY 0.680851 (-740 4060);
PAINT MONO (-740 4060);
FORCEPROP 0 LASTPIN (-750 2400) $PN 133
J 0
(-740 2410);
DISPLAY 0.680851 (-740 2410);
PAINT MONO (-740 2410);
FORCEPROP 0 LASTPIN (-750 4100) $PN 42
J 0
(-740 4110);
DISPLAY 0.680851 (-740 4110);
PAINT MONO (-740 4110);
FORCEPROP 0 LASTPIN (-750 2450) $PN 135
J 0
(-740 2460);
DISPLAY 0.680851 (-740 2460);
PAINT MONO (-740 2460);
FORCEPROP 0 LASTPIN (-750 4150) $PN 185
J 0
(-740 4160);
DISPLAY 0.680851 (-740 4160);
PAINT MONO (-740 4160);
FORCEPROP 0 LASTPIN (-750 2500) $PN 278
J 0
(-740 2510);
DISPLAY 0.680851 (-740 2510);
PAINT MONO (-740 2510);
FORCEPROP 0 LASTPIN (-750 4200) $PN 187
J 0
(-740 4210);
DISPLAY 0.680851 (-740 4210);
PAINT MONO (-740 4210);
FORCEPROP 0 LASTPIN (-750 2550) $PN 280
J 0
(-740 2560);
DISPLAY 0.680851 (-740 2560);
PAINT MONO (-740 2560);
FORCEPROP 0 LASTPIN (-750 4250) $PN 47
J 0
(-740 4260);
DISPLAY 0.680851 (-740 4260);
PAINT MONO (-740 4260);
FORCEPROP 0 LASTPIN (-750 2600) $PN 140
J 0
(-740 2610);
DISPLAY 0.680851 (-740 2610);
PAINT MONO (-740 2610);
FORCEPROP 0 LASTPIN (-750 4300) $PN 49
J 0
(-740 4310);
DISPLAY 0.680851 (-740 4310);
PAINT MONO (-740 4310);
FORCEPROP 0 LASTPIN (-750 2650) $PN 142
J 0
(-740 2660);
DISPLAY 0.680851 (-740 2660);
PAINT MONO (-740 2660);
FORCEPROP 0 LASTPIN (-750 4350) $PN 192
J 0
(-740 4360);
DISPLAY 0.680851 (-740 4360);
PAINT MONO (-740 4360);
FORCEPROP 0 LASTPIN (-750 2700) $PN 285
J 0
(-740 2710);
DISPLAY 0.680851 (-740 2710);
PAINT MONO (-740 2710);
FORCEPROP 0 LASTPIN (-750 4400) $PN 194
J 0
(-740 4410);
DISPLAY 0.680851 (-740 4410);
PAINT MONO (-740 4410);
FORCEPROP 0 LASTPIN (-750 2750) $PN 287
J 0
(-740 2760);
DISPLAY 0.680851 (-740 2760);
PAINT MONO (-740 2760);
FORCEPROP 0 LASTPIN (-1950 1900) $PN 148
J 2
(-1960 1910);
DISPLAY 0.680851 (-1960 1910);
PAINT MONO (-1960 1910);
FORCEPROP 0 LASTPIN (-1950 1800) $PN 4
J 2
(-1960 1810);
DISPLAY 0.680851 (-1960 1810);
PAINT MONO (-1960 1810);
FORCEPROP 0 LASTPIN (-1950 1850) $PN 5
J 2
(-1960 1860);
DISPLAY 0.680851 (-1960 1860);
PAINT MONO (-1960 1860);
FORCEPROP 0 LASTPIN (-1950 1000) $PN 86
J 2
(-1960 1010);
DISPLAY 0.680851 (-1960 1010);
PAINT MONO (-1960 1010);
FORCEPROP 0 LASTPIN (-1950 950) $PN 87
J 2
(-1960 960);
DISPLAY 0.680851 (-1960 960);
PAINT MONO (-1960 960);
FORCEPROP 0 LASTPIN (-1950 3600) $PN 74
J 2
(-1960 3610);
DISPLAY 0.680851 (-1960 3610);
PAINT MONO (-1960 3610);
FORCEPROP 0 LASTPIN (-1950 3550) $PN 227
J 2
(-1960 3560);
DISPLAY 0.680851 (-1960 3560);
PAINT MONO (-1960 3560);
FORCEPROP 0 LASTPIN (-1950 1550) $PN 147
J 2
(-1960 1560);
DISPLAY 0.680851 (-1960 1560);
PAINT MONO (-1960 1560);
FORCEPROP 0 LASTPIN (-1950 2100) $PN 207
J 2
(-1960 2110);
DISPLAY 0.680851 (-1960 2110);
PAINT MONO (-1960 2110);
FORCEPROP 0 LASTPIN (-1950 1150) $PN 2
J 2
(-1960 1160);
DISPLAY 0.680851 (-1960 1160);
PAINT MONO (-1960 1160);
FORCEPROP 0 LASTPIN (-1950 1200) $PN 144
J 2
(-1960 1210);
DISPLAY 0.680851 (-1960 1210);
PAINT MONO (-1960 1210);
FORCEPROP 0 LASTPIN (-1950 1250) $PN 149
J 2
(-1960 1260);
DISPLAY 0.680851 (-1960 1260);
PAINT MONO (-1960 1260);
FORCEPROP 0 LASTPIN (-1950 1300) $PN 150
J 2
(-1960 1310);
DISPLAY 0.680851 (-1960 1310);
PAINT MONO (-1960 1310);
FORCEPROP 0 LASTPIN (-1950 1350) $PN 220
J 2
(-1960 1360);
DISPLAY 0.680851 (-1960 1360);
PAINT MONO (-1960 1360);
FORCEPROP 0 LASTPIN (-1950 1400) $PN 231
J 2
(-1960 1410);
DISPLAY 0.680851 (-1960 1410);
PAINT MONO (-1960 1410);
FORCEPROP 0 LASTPIN (-1950 1450) $PN 232
J 2
(-1960 1460);
DISPLAY 0.680851 (-1960 1460);
PAINT MONO (-1960 1460);
FORCEPROP 0 LASTPIN (-1950 1950) $PN 3
J 2
(-1960 1960);
DISPLAY 0.680851 (-1960 1960);
PAINT MONO (-1960 1960);
FORCEPROP 1 LAST NEEDS_NO_SIZE TRUE
J 0
(-1350 2675);
DISPLAY 0.723404 (-1350 2675);
PAINT GREEN (-1350 2675);
DISPLAY INVISIBLE (-1350 2675);
FORCEPROP 1 LAST CDS_LMAN_SYM_OUTLINE -450,1875,450,-1875
J 0
(-1350 2675);
DISPLAY 0.468085 (-1350 2675);
PAINT GREEN (-1350 2675);
DISPLAY INVISIBLE (-1350 2675);
FORCEPROP 2 LAST CDS_LIB pure_quanta
J 0
(-1350 2675);
DISPLAY INVISIBLE (-1350 2675);
FORCEPROP 2 LAST CDS_LOCATION J4
J 0
(-1800 4900);
DISPLAY 1.021277 (-1800 4900);
DISPLAY INVISIBLE (-1800 4900);
FORCEPROP 0 LAST $SEC 1
J 0
(-1800 4900);
DISPLAY 0.680851 (-1800 4900);
PAINT MONO (-1800 4900);
DISPLAY INVISIBLE (-1800 4900);
FORCEPROP 2 LAST CDS_SEC 1
J 0
(-1800 4900);
DISPLAY 1.021277 (-1800 4900);
DISPLAY INVISIBLE (-1800 4900);
FORCEPROP 1 LAST PATH I23
J 0
(-1350 2675);
DISPLAY 0.723404 (-1350 2675);
PAINT GREEN (-1350 2675);
DISPLAY INVISIBLE (-1350 2675);
FORCEADD TAP..1
R 2
(-2175 2200);
FORCEPROP 3 LASTPIN (-2125 2200) SIG_NAME M_B_CPU0_SB_CB<0>
J 0
(-2115 2210);
DISPLAY 0.659574 (-2115 2210);
PAINT MONO (-2115 2210);
DISPLAY INVISIBLE (-2115 2210);
FORCEPROP 1 LASTPIN (-2125 2200) BN 0
J 2
(-2113 2208);
DISPLAY 0.680851 (-2113 2208);
PAINT GREEN (-2113 2208);
FORCEPROP 2 LAST CDS_LIB standard
J 0
(-2175 2200);
PAINT MONO (-2175 2200);
DISPLAY INVISIBLE (-2175 2200);
FORCEPROP 1 LAST BODY_TYPE PLUMBING
J 2
(-2175 2250);
DISPLAY 0.872340 (-2175 2250);
PAINT GREEN (-2175 2250);
DISPLAY INVISIBLE (-2175 2250);
FORCEPROP 1 LAST HDL_TAP TRUE
J 2
(-2500 2075);
DISPLAY 0.872340 (-2500 2075);
DISPLAY INVISIBLE (-2500 2075);
FORCEPROP 1 LAST PATH I24
J 2
(-2173 2200);
DISPLAY 0.872340 (-2173 2200);
PAINT GREEN (-2173 2200);
DISPLAY INVISIBLE (-2173 2200);
FORCEADD TAP..1
(-525 1200);
FORCEPROP 3 LASTPIN (-575 1200) SIG_NAME M_B_CPU0_SB_DQ<0>
J 0
(-565 1210);
DISPLAY 0.659574 (-565 1210);
PAINT MONO (-565 1210);
DISPLAY INVISIBLE (-565 1210);
FORCEPROP 1 LASTPIN (-575 1200) BN 0
J 0
(-587 1208);
DISPLAY 0.680851 (-587 1208);
PAINT GREEN (-587 1208);
FORCEPROP 2 LAST CDS_LIB standard
J 0
(-525 1200);
PAINT MONO (-525 1200);
DISPLAY INVISIBLE (-525 1200);
FORCEPROP 1 LAST BODY_TYPE PLUMBING
J 0
(-525 1250);
DISPLAY 0.872340 (-525 1250);
PAINT GREEN (-525 1250);
DISPLAY INVISIBLE (-525 1250);
FORCEPROP 1 LAST HDL_TAP TRUE
J 0
(-200 1075);
DISPLAY 0.872340 (-200 1075);
DISPLAY INVISIBLE (-200 1075);
FORCEPROP 1 LAST PATH I25
J 0
(-527 1200);
DISPLAY 0.872340 (-527 1200);
PAINT GREEN (-527 1200);
DISPLAY INVISIBLE (-527 1200);
FORCEADD TAP..1
(-525 1250);
FORCEPROP 3 LASTPIN (-575 1250) SIG_NAME M_B_CPU0_SB_DQ<1>
J 0
(-565 1260);
DISPLAY 0.659574 (-565 1260);
PAINT MONO (-565 1260);
DISPLAY INVISIBLE (-565 1260);
FORCEPROP 1 LASTPIN (-575 1250) BN 1
J 0
(-587 1258);
DISPLAY 0.680851 (-587 1258);
PAINT GREEN (-587 1258);
FORCEPROP 2 LAST CDS_LIB standard
J 0
(-525 1250);
PAINT MONO (-525 1250);
DISPLAY INVISIBLE (-525 1250);
FORCEPROP 1 LAST BODY_TYPE PLUMBING
J 0
(-525 1300);
DISPLAY 0.872340 (-525 1300);
PAINT GREEN (-525 1300);
DISPLAY INVISIBLE (-525 1300);
FORCEPROP 1 LAST HDL_TAP TRUE
J 0
(-200 1125);
DISPLAY 0.872340 (-200 1125);
DISPLAY INVISIBLE (-200 1125);
FORCEPROP 1 LAST PATH I26
J 0
(-527 1250);
DISPLAY 0.872340 (-527 1250);
PAINT GREEN (-527 1250);
DISPLAY INVISIBLE (-527 1250);
FORCEADD TAP..1
(-525 1300);
FORCEPROP 3 LASTPIN (-575 1300) SIG_NAME M_B_CPU0_SB_DQ<2>
J 0
(-565 1310);
DISPLAY 0.659574 (-565 1310);
PAINT MONO (-565 1310);
DISPLAY INVISIBLE (-565 1310);
FORCEPROP 1 LASTPIN (-575 1300) BN 2
J 0
(-587 1308);
DISPLAY 0.680851 (-587 1308);
PAINT GREEN (-587 1308);
FORCEPROP 2 LAST CDS_LIB standard
J 0
(-525 1300);
PAINT MONO (-525 1300);
DISPLAY INVISIBLE (-525 1300);
FORCEPROP 1 LAST BODY_TYPE PLUMBING
J 0
(-525 1350);
DISPLAY 0.872340 (-525 1350);
PAINT GREEN (-525 1350);
DISPLAY INVISIBLE (-525 1350);
FORCEPROP 1 LAST HDL_TAP TRUE
J 0
(-200 1175);
DISPLAY 0.872340 (-200 1175);
DISPLAY INVISIBLE (-200 1175);
FORCEPROP 1 LAST PATH I27
J 0
(-527 1300);
DISPLAY 0.872340 (-527 1300);
PAINT GREEN (-527 1300);
DISPLAY INVISIBLE (-527 1300);
FORCEADD TAP..1
(-525 1350);
FORCEPROP 3 LASTPIN (-575 1350) SIG_NAME M_B_CPU0_SB_DQ<3>
J 0
(-565 1360);
DISPLAY 0.659574 (-565 1360);
PAINT MONO (-565 1360);
DISPLAY INVISIBLE (-565 1360);
FORCEPROP 1 LASTPIN (-575 1350) BN 3
J 0
(-587 1358);
DISPLAY 0.680851 (-587 1358);
PAINT GREEN (-587 1358);
FORCEPROP 2 LAST CDS_LIB standard
J 0
(-525 1350);
PAINT MONO (-525 1350);
DISPLAY INVISIBLE (-525 1350);
FORCEPROP 1 LAST BODY_TYPE PLUMBING
J 0
(-525 1400);
DISPLAY 0.872340 (-525 1400);
PAINT GREEN (-525 1400);
DISPLAY INVISIBLE (-525 1400);
FORCEPROP 1 LAST HDL_TAP TRUE
J 0
(-200 1225);
DISPLAY 0.872340 (-200 1225);
DISPLAY INVISIBLE (-200 1225);
FORCEPROP 1 LAST PATH I28
J 0
(-527 1350);
DISPLAY 0.872340 (-527 1350);
PAINT GREEN (-527 1350);
DISPLAY INVISIBLE (-527 1350);
FORCEADD TAP..1
(-525 1450);
FORCEPROP 3 LASTPIN (-575 1450) SIG_NAME M_B_CPU0_SB_DQ<5>
J 0
(-565 1460);
DISPLAY 0.659574 (-565 1460);
PAINT MONO (-565 1460);
DISPLAY INVISIBLE (-565 1460);
FORCEPROP 1 LASTPIN (-575 1450) BN 5
J 0
(-587 1458);
DISPLAY 0.680851 (-587 1458);
PAINT GREEN (-587 1458);
FORCEPROP 2 LAST CDS_LIB standard
J 0
(-525 1450);
PAINT MONO (-525 1450);
DISPLAY INVISIBLE (-525 1450);
FORCEPROP 1 LAST BODY_TYPE PLUMBING
J 0
(-525 1500);
DISPLAY 0.872340 (-525 1500);
PAINT GREEN (-525 1500);
DISPLAY INVISIBLE (-525 1500);
FORCEPROP 1 LAST HDL_TAP TRUE
J 0
(-200 1325);
DISPLAY 0.872340 (-200 1325);
DISPLAY INVISIBLE (-200 1325);
FORCEPROP 1 LAST PATH I29
J 0
(-527 1450);
DISPLAY 0.872340 (-527 1450);
PAINT GREEN (-527 1450);
DISPLAY INVISIBLE (-527 1450);
FORCEADD OFFPAGE..2
R 2
(-3100 450);
FORCEPROP 2 LAST $XR0 85 
J 0
(-3354 450);
DISPLAY 0.638298 (-3354 450);
PAINT MONO (-3354 450);
FORCEPROP 2 LAST CDS_LIB standard
J 0
(-3100 450);
PAINT MONO (-3100 450);
DISPLAY INVISIBLE (-3100 450);
FORCEPROP 1 LAST OFFPAGE TRUE
J 2
(-3425 325);
DISPLAY 0.872340 (-3425 325);
DISPLAY INVISIBLE (-3425 325);
FORCEPROP 1 LAST COMMENT_BODY TRUE
J 2
(-3055 355);
DISPLAY 0.872340 (-3055 355);
PAINT GREEN (-3055 355);
DISPLAY INVISIBLE (-3055 355);
FORCEPROP 2 LAST PATH I3
J 0
(-3050 525);
DISPLAY 1.021277 (-3050 525);
DISPLAY INVISIBLE (-3050 525);
FORCEADD TAP..1
(-525 1400);
FORCEPROP 3 LASTPIN (-575 1400) SIG_NAME M_B_CPU0_SB_DQ<4>
J 0
(-565 1410);
DISPLAY 0.659574 (-565 1410);
PAINT MONO (-565 1410);
DISPLAY INVISIBLE (-565 1410);
FORCEPROP 1 LASTPIN (-575 1400) BN 4
J 0
(-587 1408);
DISPLAY 0.680851 (-587 1408);
PAINT GREEN (-587 1408);
FORCEPROP 2 LAST CDS_LIB standard
J 0
(-525 1400);
PAINT MONO (-525 1400);
DISPLAY INVISIBLE (-525 1400);
FORCEPROP 1 LAST BODY_TYPE PLUMBING
J 0
(-525 1450);
DISPLAY 0.872340 (-525 1450);
PAINT GREEN (-525 1450);
DISPLAY INVISIBLE (-525 1450);
FORCEPROP 1 LAST HDL_TAP TRUE
J 0
(-200 1275);
DISPLAY 0.872340 (-200 1275);
DISPLAY INVISIBLE (-200 1275);
FORCEPROP 1 LAST PATH I30
J 0
(-527 1400);
DISPLAY 0.872340 (-527 1400);
PAINT GREEN (-527 1400);
DISPLAY INVISIBLE (-527 1400);
FORCEADD TAP..1
(-525 1500);
FORCEPROP 3 LASTPIN (-575 1500) SIG_NAME M_B_CPU0_SB_DQ<6>
J 0
(-565 1510);
DISPLAY 0.659574 (-565 1510);
PAINT MONO (-565 1510);
DISPLAY INVISIBLE (-565 1510);
FORCEPROP 1 LASTPIN (-575 1500) BN 6
J 0
(-587 1508);
DISPLAY 0.680851 (-587 1508);
PAINT GREEN (-587 1508);
FORCEPROP 2 LAST CDS_LIB standard
J 0
(-525 1500);
PAINT MONO (-525 1500);
DISPLAY INVISIBLE (-525 1500);
FORCEPROP 1 LAST BODY_TYPE PLUMBING
J 0
(-525 1550);
DISPLAY 0.872340 (-525 1550);
PAINT GREEN (-525 1550);
DISPLAY INVISIBLE (-525 1550);
FORCEPROP 1 LAST HDL_TAP TRUE
J 0
(-200 1375);
DISPLAY 0.872340 (-200 1375);
DISPLAY INVISIBLE (-200 1375);
FORCEPROP 1 LAST PATH I31
J 0
(-527 1500);
DISPLAY 0.872340 (-527 1500);
PAINT GREEN (-527 1500);
DISPLAY INVISIBLE (-527 1500);
FORCEADD TAP..1
(-525 1600);
FORCEPROP 3 LASTPIN (-575 1600) SIG_NAME M_B_CPU0_SB_DQ<8>
J 0
(-565 1610);
DISPLAY 0.659574 (-565 1610);
PAINT MONO (-565 1610);
DISPLAY INVISIBLE (-565 1610);
FORCEPROP 1 LASTPIN (-575 1600) BN 8
J 0
(-587 1608);
DISPLAY 0.680851 (-587 1608);
PAINT GREEN (-587 1608);
FORCEPROP 2 LAST CDS_LIB standard
J 0
(-525 1600);
PAINT MONO (-525 1600);
DISPLAY INVISIBLE (-525 1600);
FORCEPROP 1 LAST BODY_TYPE PLUMBING
J 0
(-525 1650);
DISPLAY 0.872340 (-525 1650);
PAINT GREEN (-525 1650);
DISPLAY INVISIBLE (-525 1650);
FORCEPROP 1 LAST HDL_TAP TRUE
J 0
(-200 1475);
DISPLAY 0.872340 (-200 1475);
DISPLAY INVISIBLE (-200 1475);
FORCEPROP 1 LAST PATH I32
J 0
(-527 1600);
DISPLAY 0.872340 (-527 1600);
PAINT GREEN (-527 1600);
DISPLAY INVISIBLE (-527 1600);
FORCEADD TAP..1
(-525 1550);
FORCEPROP 3 LASTPIN (-575 1550) SIG_NAME M_B_CPU0_SB_DQ<7>
J 0
(-565 1560);
DISPLAY 0.659574 (-565 1560);
PAINT MONO (-565 1560);
DISPLAY INVISIBLE (-565 1560);
FORCEPROP 1 LASTPIN (-575 1550) BN 7
J 0
(-587 1558);
DISPLAY 0.680851 (-587 1558);
PAINT GREEN (-587 1558);
FORCEPROP 2 LAST CDS_LIB standard
J 0
(-525 1550);
PAINT MONO (-525 1550);
DISPLAY INVISIBLE (-525 1550);
FORCEPROP 1 LAST BODY_TYPE PLUMBING
J 0
(-525 1600);
DISPLAY 0.872340 (-525 1600);
PAINT GREEN (-525 1600);
DISPLAY INVISIBLE (-525 1600);
FORCEPROP 1 LAST HDL_TAP TRUE
J 0
(-200 1425);
DISPLAY 0.872340 (-200 1425);
DISPLAY INVISIBLE (-200 1425);
FORCEPROP 1 LAST PATH I33
J 0
(-527 1550);
DISPLAY 0.872340 (-527 1550);
PAINT GREEN (-527 1550);
DISPLAY INVISIBLE (-527 1550);
FORCEADD TAP..1
(-525 1700);
FORCEPROP 3 LASTPIN (-575 1700) SIG_NAME M_B_CPU0_SB_DQ<10>
J 0
(-565 1710);
DISPLAY 0.659574 (-565 1710);
PAINT MONO (-565 1710);
DISPLAY INVISIBLE (-565 1710);
FORCEPROP 1 LASTPIN (-575 1700) BN 10
J 0
(-587 1708);
DISPLAY 0.680851 (-587 1708);
PAINT GREEN (-587 1708);
FORCEPROP 2 LAST CDS_LIB standard
J 0
(-525 1700);
PAINT MONO (-525 1700);
DISPLAY INVISIBLE (-525 1700);
FORCEPROP 1 LAST BODY_TYPE PLUMBING
J 0
(-525 1750);
DISPLAY 0.872340 (-525 1750);
PAINT GREEN (-525 1750);
DISPLAY INVISIBLE (-525 1750);
FORCEPROP 1 LAST HDL_TAP TRUE
J 0
(-200 1575);
DISPLAY 0.872340 (-200 1575);
DISPLAY INVISIBLE (-200 1575);
FORCEPROP 1 LAST PATH I34
J 0
(-527 1700);
DISPLAY 0.872340 (-527 1700);
PAINT GREEN (-527 1700);
DISPLAY INVISIBLE (-527 1700);
FORCEADD TAP..1
(-525 1650);
FORCEPROP 3 LASTPIN (-575 1650) SIG_NAME M_B_CPU0_SB_DQ<9>
J 0
(-565 1660);
DISPLAY 0.659574 (-565 1660);
PAINT MONO (-565 1660);
DISPLAY INVISIBLE (-565 1660);
FORCEPROP 1 LASTPIN (-575 1650) BN 9
J 0
(-587 1658);
DISPLAY 0.680851 (-587 1658);
PAINT GREEN (-587 1658);
FORCEPROP 2 LAST CDS_LIB standard
J 0
(-525 1650);
PAINT MONO (-525 1650);
DISPLAY INVISIBLE (-525 1650);
FORCEPROP 1 LAST BODY_TYPE PLUMBING
J 0
(-525 1700);
DISPLAY 0.872340 (-525 1700);
PAINT GREEN (-525 1700);
DISPLAY INVISIBLE (-525 1700);
FORCEPROP 1 LAST HDL_TAP TRUE
J 0
(-200 1525);
DISPLAY 0.872340 (-200 1525);
DISPLAY INVISIBLE (-200 1525);
FORCEPROP 1 LAST PATH I35
J 0
(-527 1650);
DISPLAY 0.872340 (-527 1650);
PAINT GREEN (-527 1650);
DISPLAY INVISIBLE (-527 1650);
FORCEADD TAP..1
(-525 1750);
FORCEPROP 3 LASTPIN (-575 1750) SIG_NAME M_B_CPU0_SB_DQ<11>
J 0
(-565 1760);
DISPLAY 0.659574 (-565 1760);
PAINT MONO (-565 1760);
DISPLAY INVISIBLE (-565 1760);
FORCEPROP 1 LASTPIN (-575 1750) BN 11
J 0
(-587 1758);
DISPLAY 0.680851 (-587 1758);
PAINT GREEN (-587 1758);
FORCEPROP 2 LAST CDS_LIB standard
J 0
(-525 1750);
PAINT MONO (-525 1750);
DISPLAY INVISIBLE (-525 1750);
FORCEPROP 1 LAST BODY_TYPE PLUMBING
J 0
(-525 1800);
DISPLAY 0.872340 (-525 1800);
PAINT GREEN (-525 1800);
DISPLAY INVISIBLE (-525 1800);
FORCEPROP 1 LAST HDL_TAP TRUE
J 0
(-200 1625);
DISPLAY 0.872340 (-200 1625);
DISPLAY INVISIBLE (-200 1625);
FORCEPROP 1 LAST PATH I36
J 0
(-527 1750);
DISPLAY 0.872340 (-527 1750);
PAINT GREEN (-527 1750);
DISPLAY INVISIBLE (-527 1750);
FORCEADD TAP..1
(-525 1800);
FORCEPROP 3 LASTPIN (-575 1800) SIG_NAME M_B_CPU0_SB_DQ<12>
J 0
(-565 1810);
DISPLAY 0.659574 (-565 1810);
PAINT MONO (-565 1810);
DISPLAY INVISIBLE (-565 1810);
FORCEPROP 1 LASTPIN (-575 1800) BN 12
J 0
(-587 1808);
DISPLAY 0.680851 (-587 1808);
PAINT GREEN (-587 1808);
FORCEPROP 2 LAST CDS_LIB standard
J 0
(-525 1800);
PAINT MONO (-525 1800);
DISPLAY INVISIBLE (-525 1800);
FORCEPROP 1 LAST BODY_TYPE PLUMBING
J 0
(-525 1850);
DISPLAY 0.872340 (-525 1850);
PAINT GREEN (-525 1850);
DISPLAY INVISIBLE (-525 1850);
FORCEPROP 1 LAST HDL_TAP TRUE
J 0
(-200 1675);
DISPLAY 0.872340 (-200 1675);
DISPLAY INVISIBLE (-200 1675);
FORCEPROP 1 LAST PATH I37
J 0
(-527 1800);
DISPLAY 0.872340 (-527 1800);
PAINT GREEN (-527 1800);
DISPLAY INVISIBLE (-527 1800);
FORCEADD TAP..1
(-525 1850);
FORCEPROP 3 LASTPIN (-575 1850) SIG_NAME M_B_CPU0_SB_DQ<13>
J 0
(-565 1860);
DISPLAY 0.659574 (-565 1860);
PAINT MONO (-565 1860);
DISPLAY INVISIBLE (-565 1860);
FORCEPROP 1 LASTPIN (-575 1850) BN 13
J 0
(-587 1858);
DISPLAY 0.680851 (-587 1858);
PAINT GREEN (-587 1858);
FORCEPROP 2 LAST CDS_LIB standard
J 0
(-525 1850);
PAINT MONO (-525 1850);
DISPLAY INVISIBLE (-525 1850);
FORCEPROP 1 LAST BODY_TYPE PLUMBING
J 0
(-525 1900);
DISPLAY 0.872340 (-525 1900);
PAINT GREEN (-525 1900);
DISPLAY INVISIBLE (-525 1900);
FORCEPROP 1 LAST HDL_TAP TRUE
J 0
(-200 1725);
DISPLAY 0.872340 (-200 1725);
DISPLAY INVISIBLE (-200 1725);
FORCEPROP 1 LAST PATH I38
J 0
(-527 1850);
DISPLAY 0.872340 (-527 1850);
PAINT GREEN (-527 1850);
DISPLAY INVISIBLE (-527 1850);
FORCEADD TAP..1
(-525 1900);
FORCEPROP 3 LASTPIN (-575 1900) SIG_NAME M_B_CPU0_SB_DQ<14>
J 0
(-565 1910);
DISPLAY 0.659574 (-565 1910);
PAINT MONO (-565 1910);
DISPLAY INVISIBLE (-565 1910);
FORCEPROP 1 LASTPIN (-575 1900) BN 14
J 0
(-587 1908);
DISPLAY 0.680851 (-587 1908);
PAINT GREEN (-587 1908);
FORCEPROP 2 LAST CDS_LIB standard
J 0
(-525 1900);
PAINT MONO (-525 1900);
DISPLAY INVISIBLE (-525 1900);
FORCEPROP 1 LAST BODY_TYPE PLUMBING
J 0
(-525 1950);
DISPLAY 0.872340 (-525 1950);
PAINT GREEN (-525 1950);
DISPLAY INVISIBLE (-525 1950);
FORCEPROP 1 LAST HDL_TAP TRUE
J 0
(-200 1775);
DISPLAY 0.872340 (-200 1775);
DISPLAY INVISIBLE (-200 1775);
FORCEPROP 1 LAST PATH I39
J 0
(-527 1900);
DISPLAY 0.872340 (-527 1900);
PAINT GREEN (-527 1900);
DISPLAY INVISIBLE (-527 1900);
FORCEADD OFFPAGE..2
R 2
(-3100 950);
FORCEPROP 2 LAST $XR0 21 
J 0
(-3354 950);
DISPLAY 0.638298 (-3354 950);
PAINT MONO (-3354 950);
FORCEPROP 2 LAST CDS_LIB standard
J 0
(-3100 950);
PAINT MONO (-3100 950);
DISPLAY INVISIBLE (-3100 950);
FORCEPROP 1 LAST OFFPAGE TRUE
J 2
(-3425 825);
DISPLAY 0.872340 (-3425 825);
DISPLAY INVISIBLE (-3425 825);
FORCEPROP 1 LAST COMMENT_BODY TRUE
J 2
(-3055 855);
DISPLAY 0.872340 (-3055 855);
PAINT GREEN (-3055 855);
DISPLAY INVISIBLE (-3055 855);
FORCEPROP 2 LAST PATH I4
J 0
(-3050 1025);
DISPLAY 1.021277 (-3050 1025);
DISPLAY INVISIBLE (-3050 1025);
FORCEADD TAP..1
(-525 1950);
FORCEPROP 3 LASTPIN (-575 1950) SIG_NAME M_B_CPU0_SB_DQ<15>
J 0
(-565 1960);
DISPLAY 0.659574 (-565 1960);
PAINT MONO (-565 1960);
DISPLAY INVISIBLE (-565 1960);
FORCEPROP 1 LASTPIN (-575 1950) BN 15
J 0
(-587 1958);
DISPLAY 0.680851 (-587 1958);
PAINT GREEN (-587 1958);
FORCEPROP 2 LAST CDS_LIB standard
J 0
(-525 1950);
PAINT MONO (-525 1950);
DISPLAY INVISIBLE (-525 1950);
FORCEPROP 1 LAST BODY_TYPE PLUMBING
J 0
(-525 2000);
DISPLAY 0.872340 (-525 2000);
PAINT GREEN (-525 2000);
DISPLAY INVISIBLE (-525 2000);
FORCEPROP 1 LAST HDL_TAP TRUE
J 0
(-200 1825);
DISPLAY 0.872340 (-200 1825);
DISPLAY INVISIBLE (-200 1825);
FORCEPROP 1 LAST PATH I40
J 0
(-527 1950);
DISPLAY 0.872340 (-527 1950);
PAINT GREEN (-527 1950);
DISPLAY INVISIBLE (-527 1950);
FORCEADD TAP..1
(-525 2000);
FORCEPROP 3 LASTPIN (-575 2000) SIG_NAME M_B_CPU0_SB_DQ<16>
J 0
(-565 2010);
DISPLAY 0.659574 (-565 2010);
PAINT MONO (-565 2010);
DISPLAY INVISIBLE (-565 2010);
FORCEPROP 1 LASTPIN (-575 2000) BN 16
J 0
(-587 2008);
DISPLAY 0.680851 (-587 2008);
PAINT GREEN (-587 2008);
FORCEPROP 2 LAST CDS_LIB standard
J 0
(-525 2000);
PAINT MONO (-525 2000);
DISPLAY INVISIBLE (-525 2000);
FORCEPROP 1 LAST BODY_TYPE PLUMBING
J 0
(-525 2050);
DISPLAY 0.872340 (-525 2050);
PAINT GREEN (-525 2050);
DISPLAY INVISIBLE (-525 2050);
FORCEPROP 1 LAST HDL_TAP TRUE
J 0
(-200 1875);
DISPLAY 0.872340 (-200 1875);
DISPLAY INVISIBLE (-200 1875);
FORCEPROP 1 LAST PATH I41
J 0
(-527 2000);
DISPLAY 0.872340 (-527 2000);
PAINT GREEN (-527 2000);
DISPLAY INVISIBLE (-527 2000);
FORCEADD TAP..1
(-525 2050);
FORCEPROP 3 LASTPIN (-575 2050) SIG_NAME M_B_CPU0_SB_DQ<17>
J 0
(-565 2060);
DISPLAY 0.659574 (-565 2060);
PAINT MONO (-565 2060);
DISPLAY INVISIBLE (-565 2060);
FORCEPROP 1 LASTPIN (-575 2050) BN 17
J 0
(-587 2058);
DISPLAY 0.680851 (-587 2058);
PAINT GREEN (-587 2058);
FORCEPROP 2 LAST CDS_LIB standard
J 0
(-525 2050);
PAINT MONO (-525 2050);
DISPLAY INVISIBLE (-525 2050);
FORCEPROP 1 LAST BODY_TYPE PLUMBING
J 0
(-525 2100);
DISPLAY 0.872340 (-525 2100);
PAINT GREEN (-525 2100);
DISPLAY INVISIBLE (-525 2100);
FORCEPROP 1 LAST HDL_TAP TRUE
J 0
(-200 1925);
DISPLAY 0.872340 (-200 1925);
DISPLAY INVISIBLE (-200 1925);
FORCEPROP 1 LAST PATH I42
J 0
(-527 2050);
DISPLAY 0.872340 (-527 2050);
PAINT GREEN (-527 2050);
DISPLAY INVISIBLE (-527 2050);
FORCEADD TAP..1
(-525 2100);
FORCEPROP 3 LASTPIN (-575 2100) SIG_NAME M_B_CPU0_SB_DQ<18>
J 0
(-565 2110);
DISPLAY 0.659574 (-565 2110);
PAINT MONO (-565 2110);
DISPLAY INVISIBLE (-565 2110);
FORCEPROP 1 LASTPIN (-575 2100) BN 18
J 0
(-587 2108);
DISPLAY 0.680851 (-587 2108);
PAINT GREEN (-587 2108);
FORCEPROP 2 LAST CDS_LIB standard
J 0
(-525 2100);
PAINT MONO (-525 2100);
DISPLAY INVISIBLE (-525 2100);
FORCEPROP 1 LAST BODY_TYPE PLUMBING
J 0
(-525 2150);
DISPLAY 0.872340 (-525 2150);
PAINT GREEN (-525 2150);
DISPLAY INVISIBLE (-525 2150);
FORCEPROP 1 LAST HDL_TAP TRUE
J 0
(-200 1975);
DISPLAY 0.872340 (-200 1975);
DISPLAY INVISIBLE (-200 1975);
FORCEPROP 1 LAST PATH I43
J 0
(-527 2100);
DISPLAY 0.872340 (-527 2100);
PAINT GREEN (-527 2100);
DISPLAY INVISIBLE (-527 2100);
FORCEADD TAP..1
(-525 2200);
FORCEPROP 3 LASTPIN (-575 2200) SIG_NAME M_B_CPU0_SB_DQ<20>
J 0
(-565 2210);
DISPLAY 0.659574 (-565 2210);
PAINT MONO (-565 2210);
DISPLAY INVISIBLE (-565 2210);
FORCEPROP 1 LASTPIN (-575 2200) BN 20
J 0
(-587 2208);
DISPLAY 0.680851 (-587 2208);
PAINT GREEN (-587 2208);
FORCEPROP 2 LAST CDS_LIB standard
J 0
(-525 2200);
PAINT MONO (-525 2200);
DISPLAY INVISIBLE (-525 2200);
FORCEPROP 1 LAST BODY_TYPE PLUMBING
J 0
(-525 2250);
DISPLAY 0.872340 (-525 2250);
PAINT GREEN (-525 2250);
DISPLAY INVISIBLE (-525 2250);
FORCEPROP 1 LAST HDL_TAP TRUE
J 0
(-200 2075);
DISPLAY 0.872340 (-200 2075);
DISPLAY INVISIBLE (-200 2075);
FORCEPROP 1 LAST PATH I44
J 0
(-527 2200);
DISPLAY 0.872340 (-527 2200);
PAINT GREEN (-527 2200);
DISPLAY INVISIBLE (-527 2200);
FORCEADD TAP..1
(-525 2150);
FORCEPROP 3 LASTPIN (-575 2150) SIG_NAME M_B_CPU0_SB_DQ<19>
J 0
(-565 2160);
DISPLAY 0.659574 (-565 2160);
PAINT MONO (-565 2160);
DISPLAY INVISIBLE (-565 2160);
FORCEPROP 1 LASTPIN (-575 2150) BN 19
J 0
(-587 2158);
DISPLAY 0.680851 (-587 2158);
PAINT GREEN (-587 2158);
FORCEPROP 2 LAST CDS_LIB standard
J 0
(-525 2150);
PAINT MONO (-525 2150);
DISPLAY INVISIBLE (-525 2150);
FORCEPROP 1 LAST BODY_TYPE PLUMBING
J 0
(-525 2200);
DISPLAY 0.872340 (-525 2200);
PAINT GREEN (-525 2200);
DISPLAY INVISIBLE (-525 2200);
FORCEPROP 1 LAST HDL_TAP TRUE
J 0
(-200 2025);
DISPLAY 0.872340 (-200 2025);
DISPLAY INVISIBLE (-200 2025);
FORCEPROP 1 LAST PATH I45
J 0
(-527 2150);
DISPLAY 0.872340 (-527 2150);
PAINT GREEN (-527 2150);
DISPLAY INVISIBLE (-527 2150);
FORCEADD TAP..1
R 2
(-2175 2350);
FORCEPROP 3 LASTPIN (-2125 2350) SIG_NAME M_B_CPU0_SB_CB<3>
J 0
(-2115 2360);
DISPLAY 0.659574 (-2115 2360);
PAINT MONO (-2115 2360);
DISPLAY INVISIBLE (-2115 2360);
FORCEPROP 1 LASTPIN (-2125 2350) BN 3
J 2
(-2113 2358);
DISPLAY 0.680851 (-2113 2358);
PAINT GREEN (-2113 2358);
FORCEPROP 2 LAST CDS_LIB standard
J 0
(-2175 2350);
DISPLAY INVISIBLE (-2175 2350);
FORCEPROP 1 LAST BODY_TYPE PLUMBING
J 2
(-2175 2400);
DISPLAY 0.872340 (-2175 2400);
PAINT GREEN (-2175 2400);
DISPLAY INVISIBLE (-2175 2400);
FORCEPROP 1 LAST HDL_TAP TRUE
J 2
(-2500 2225);
DISPLAY 0.872340 (-2500 2225);
DISPLAY INVISIBLE (-2500 2225);
FORCEPROP 1 LAST PATH I46
J 2
(-2173 2350);
DISPLAY 0.872340 (-2173 2350);
PAINT GREEN (-2173 2350);
DISPLAY INVISIBLE (-2173 2350);
FORCEADD TAP..1
R 2
(-2175 2300);
FORCEPROP 3 LASTPIN (-2125 2300) SIG_NAME M_B_CPU0_SB_CB<2>
J 0
(-2115 2310);
DISPLAY 0.659574 (-2115 2310);
PAINT MONO (-2115 2310);
DISPLAY INVISIBLE (-2115 2310);
FORCEPROP 1 LASTPIN (-2125 2300) BN 2
J 2
(-2113 2308);
DISPLAY 0.680851 (-2113 2308);
PAINT GREEN (-2113 2308);
FORCEPROP 2 LAST CDS_LIB standard
J 0
(-2175 2300);
DISPLAY INVISIBLE (-2175 2300);
FORCEPROP 1 LAST BODY_TYPE PLUMBING
J 2
(-2175 2350);
DISPLAY 0.872340 (-2175 2350);
PAINT GREEN (-2175 2350);
DISPLAY INVISIBLE (-2175 2350);
FORCEPROP 1 LAST HDL_TAP TRUE
J 2
(-2500 2175);
DISPLAY 0.872340 (-2500 2175);
DISPLAY INVISIBLE (-2500 2175);
FORCEPROP 1 LAST PATH I47
J 2
(-2173 2300);
DISPLAY 0.872340 (-2173 2300);
PAINT GREEN (-2173 2300);
DISPLAY INVISIBLE (-2173 2300);
FORCEADD TAP..1
R 2
(-2175 2250);
FORCEPROP 3 LASTPIN (-2125 2250) SIG_NAME M_B_CPU0_SB_CB<1>
J 0
(-2115 2260);
DISPLAY 0.659574 (-2115 2260);
PAINT MONO (-2115 2260);
DISPLAY INVISIBLE (-2115 2260);
FORCEPROP 1 LASTPIN (-2125 2250) BN 1
J 2
(-2113 2258);
DISPLAY 0.680851 (-2113 2258);
PAINT GREEN (-2113 2258);
FORCEPROP 2 LAST CDS_LIB standard
J 0
(-2175 2250);
DISPLAY INVISIBLE (-2175 2250);
FORCEPROP 1 LAST BODY_TYPE PLUMBING
J 2
(-2175 2300);
DISPLAY 0.872340 (-2175 2300);
PAINT GREEN (-2175 2300);
DISPLAY INVISIBLE (-2175 2300);
FORCEPROP 1 LAST HDL_TAP TRUE
J 2
(-2500 2125);
DISPLAY 0.872340 (-2500 2125);
DISPLAY INVISIBLE (-2500 2125);
FORCEPROP 1 LAST PATH I48
J 2
(-2173 2250);
DISPLAY 0.872340 (-2173 2250);
PAINT GREEN (-2173 2250);
DISPLAY INVISIBLE (-2173 2250);
FORCEADD TAP..1
R 2
(-2175 2450);
FORCEPROP 3 LASTPIN (-2125 2450) SIG_NAME M_B_CPU0_SB_CB<5>
J 0
(-2115 2460);
DISPLAY 0.659574 (-2115 2460);
PAINT MONO (-2115 2460);
DISPLAY INVISIBLE (-2115 2460);
FORCEPROP 1 LASTPIN (-2125 2450) BN 5
J 2
(-2113 2458);
DISPLAY 0.680851 (-2113 2458);
PAINT GREEN (-2113 2458);
FORCEPROP 2 LAST CDS_LIB standard
J 0
(-2175 2450);
DISPLAY INVISIBLE (-2175 2450);
FORCEPROP 1 LAST BODY_TYPE PLUMBING
J 2
(-2175 2500);
DISPLAY 0.872340 (-2175 2500);
PAINT GREEN (-2175 2500);
DISPLAY INVISIBLE (-2175 2500);
FORCEPROP 1 LAST HDL_TAP TRUE
J 2
(-2500 2325);
DISPLAY 0.872340 (-2500 2325);
DISPLAY INVISIBLE (-2500 2325);
FORCEPROP 1 LAST PATH I49
J 2
(-2173 2450);
DISPLAY 0.872340 (-2173 2450);
PAINT GREEN (-2173 2450);
DISPLAY INVISIBLE (-2173 2450);
FORCEADD OFFPAGE..2
R 2
(-3100 1000);
FORCEPROP 2 LAST $XR0 21 
J 0
(-3354 1000);
DISPLAY 0.638298 (-3354 1000);
PAINT MONO (-3354 1000);
FORCEPROP 2 LAST CDS_LIB standard
J 0
(-3100 1000);
PAINT MONO (-3100 1000);
DISPLAY INVISIBLE (-3100 1000);
FORCEPROP 1 LAST OFFPAGE TRUE
J 2
(-3425 875);
DISPLAY 0.872340 (-3425 875);
DISPLAY INVISIBLE (-3425 875);
FORCEPROP 1 LAST COMMENT_BODY TRUE
J 2
(-3055 905);
DISPLAY 0.872340 (-3055 905);
PAINT GREEN (-3055 905);
DISPLAY INVISIBLE (-3055 905);
FORCEPROP 2 LAST PATH I5
J 0
(-3050 1075);
DISPLAY 1.021277 (-3050 1075);
DISPLAY INVISIBLE (-3050 1075);
FORCEADD TAP..1
R 2
(-2175 2400);
FORCEPROP 3 LASTPIN (-2125 2400) SIG_NAME M_B_CPU0_SB_CB<4>
J 0
(-2115 2410);
DISPLAY 0.659574 (-2115 2410);
PAINT MONO (-2115 2410);
DISPLAY INVISIBLE (-2115 2410);
FORCEPROP 1 LASTPIN (-2125 2400) BN 4
J 2
(-2113 2408);
DISPLAY 0.680851 (-2113 2408);
PAINT GREEN (-2113 2408);
FORCEPROP 2 LAST CDS_LIB standard
J 0
(-2175 2400);
DISPLAY INVISIBLE (-2175 2400);
FORCEPROP 1 LAST BODY_TYPE PLUMBING
J 2
(-2175 2450);
DISPLAY 0.872340 (-2175 2450);
PAINT GREEN (-2175 2450);
DISPLAY INVISIBLE (-2175 2450);
FORCEPROP 1 LAST HDL_TAP TRUE
J 2
(-2500 2275);
DISPLAY 0.872340 (-2500 2275);
DISPLAY INVISIBLE (-2500 2275);
FORCEPROP 1 LAST PATH I50
J 2
(-2173 2400);
DISPLAY 0.872340 (-2173 2400);
PAINT GREEN (-2173 2400);
DISPLAY INVISIBLE (-2173 2400);
FORCEADD TAP..1
R 2
(-2175 2500);
FORCEPROP 3 LASTPIN (-2125 2500) SIG_NAME M_B_CPU0_SB_CB<6>
J 0
(-2115 2510);
DISPLAY 0.659574 (-2115 2510);
PAINT MONO (-2115 2510);
DISPLAY INVISIBLE (-2115 2510);
FORCEPROP 1 LASTPIN (-2125 2500) BN 6
J 2
(-2113 2508);
DISPLAY 0.680851 (-2113 2508);
PAINT GREEN (-2113 2508);
FORCEPROP 2 LAST CDS_LIB standard
J 0
(-2175 2500);
DISPLAY INVISIBLE (-2175 2500);
FORCEPROP 1 LAST BODY_TYPE PLUMBING
J 2
(-2175 2550);
DISPLAY 0.872340 (-2175 2550);
PAINT GREEN (-2175 2550);
DISPLAY INVISIBLE (-2175 2550);
FORCEPROP 1 LAST HDL_TAP TRUE
J 2
(-2500 2375);
DISPLAY 0.872340 (-2500 2375);
DISPLAY INVISIBLE (-2500 2375);
FORCEPROP 1 LAST PATH I51
J 2
(-2173 2500);
DISPLAY 0.872340 (-2173 2500);
PAINT GREEN (-2173 2500);
DISPLAY INVISIBLE (-2173 2500);
FORCEADD TAP..1
R 2
(-2175 2550);
FORCEPROP 3 LASTPIN (-2125 2550) SIG_NAME M_B_CPU0_SB_CB<7>
J 0
(-2115 2560);
DISPLAY 0.659574 (-2115 2560);
PAINT MONO (-2115 2560);
DISPLAY INVISIBLE (-2115 2560);
FORCEPROP 1 LASTPIN (-2125 2550) BN 7
J 2
(-2113 2558);
DISPLAY 0.680851 (-2113 2558);
PAINT GREEN (-2113 2558);
FORCEPROP 2 LAST CDS_LIB standard
J 0
(-2175 2550);
DISPLAY INVISIBLE (-2175 2550);
FORCEPROP 1 LAST BODY_TYPE PLUMBING
J 2
(-2175 2600);
DISPLAY 0.872340 (-2175 2600);
PAINT GREEN (-2175 2600);
DISPLAY INVISIBLE (-2175 2600);
FORCEPROP 1 LAST HDL_TAP TRUE
J 2
(-2500 2425);
DISPLAY 0.872340 (-2500 2425);
DISPLAY INVISIBLE (-2500 2425);
FORCEPROP 1 LAST PATH I52
J 2
(-2173 2550);
DISPLAY 0.872340 (-2173 2550);
PAINT GREEN (-2173 2550);
DISPLAY INVISIBLE (-2173 2550);
FORCEADD TAP..1
R 2
(-2175 2700);
FORCEPROP 3 LASTPIN (-2125 2700) SIG_NAME M_B_CPU0_SA_CB<1>
J 0
(-2115 2710);
DISPLAY 0.659574 (-2115 2710);
PAINT MONO (-2115 2710);
DISPLAY INVISIBLE (-2115 2710);
FORCEPROP 1 LASTPIN (-2125 2700) BN 1
J 2
(-2113 2708);
DISPLAY 0.680851 (-2113 2708);
PAINT GREEN (-2113 2708);
FORCEPROP 2 LAST CDS_LIB standard
J 0
(-2175 2700);
DISPLAY INVISIBLE (-2175 2700);
FORCEPROP 1 LAST BODY_TYPE PLUMBING
J 2
(-2175 2750);
DISPLAY 0.872340 (-2175 2750);
PAINT GREEN (-2175 2750);
DISPLAY INVISIBLE (-2175 2750);
FORCEPROP 1 LAST HDL_TAP TRUE
J 2
(-2500 2575);
DISPLAY 0.872340 (-2500 2575);
DISPLAY INVISIBLE (-2500 2575);
FORCEPROP 1 LAST PATH I53
J 2
(-2173 2700);
DISPLAY 0.872340 (-2173 2700);
PAINT GREEN (-2173 2700);
DISPLAY INVISIBLE (-2173 2700);
FORCEADD TAP..1
R 2
(-2175 2650);
FORCEPROP 3 LASTPIN (-2125 2650) SIG_NAME M_B_CPU0_SA_CB<0>
J 0
(-2115 2660);
DISPLAY 0.659574 (-2115 2660);
PAINT MONO (-2115 2660);
DISPLAY INVISIBLE (-2115 2660);
FORCEPROP 1 LASTPIN (-2125 2650) BN 0
J 2
(-2113 2658);
DISPLAY 0.680851 (-2113 2658);
PAINT GREEN (-2113 2658);
FORCEPROP 2 LAST CDS_LIB standard
J 0
(-2175 2650);
PAINT MONO (-2175 2650);
DISPLAY INVISIBLE (-2175 2650);
FORCEPROP 1 LAST BODY_TYPE PLUMBING
J 2
(-2175 2700);
DISPLAY 0.872340 (-2175 2700);
PAINT GREEN (-2175 2700);
DISPLAY INVISIBLE (-2175 2700);
FORCEPROP 1 LAST HDL_TAP TRUE
J 2
(-2500 2525);
DISPLAY 0.872340 (-2500 2525);
DISPLAY INVISIBLE (-2500 2525);
FORCEPROP 1 LAST PATH I54
J 2
(-2173 2650);
DISPLAY 0.872340 (-2173 2650);
PAINT GREEN (-2173 2650);
DISPLAY INVISIBLE (-2173 2650);
FORCEADD TAP..1
R 2
(-2175 2750);
FORCEPROP 3 LASTPIN (-2125 2750) SIG_NAME M_B_CPU0_SA_CB<2>
J 0
(-2115 2760);
DISPLAY 0.659574 (-2115 2760);
PAINT MONO (-2115 2760);
DISPLAY INVISIBLE (-2115 2760);
FORCEPROP 1 LASTPIN (-2125 2750) BN 2
J 2
(-2113 2758);
DISPLAY 0.680851 (-2113 2758);
PAINT GREEN (-2113 2758);
FORCEPROP 2 LAST CDS_LIB standard
J 0
(-2175 2750);
DISPLAY INVISIBLE (-2175 2750);
FORCEPROP 1 LAST BODY_TYPE PLUMBING
J 2
(-2175 2800);
DISPLAY 0.872340 (-2175 2800);
PAINT GREEN (-2175 2800);
DISPLAY INVISIBLE (-2175 2800);
FORCEPROP 1 LAST HDL_TAP TRUE
J 2
(-2500 2625);
DISPLAY 0.872340 (-2500 2625);
DISPLAY INVISIBLE (-2500 2625);
FORCEPROP 1 LAST PATH I55
J 2
(-2173 2750);
DISPLAY 0.872340 (-2173 2750);
PAINT GREEN (-2173 2750);
DISPLAY INVISIBLE (-2173 2750);
FORCEADD TAP..1
R 2
(-2175 2800);
FORCEPROP 3 LASTPIN (-2125 2800) SIG_NAME M_B_CPU0_SA_CB<3>
J 0
(-2115 2810);
DISPLAY 0.659574 (-2115 2810);
PAINT MONO (-2115 2810);
DISPLAY INVISIBLE (-2115 2810);
FORCEPROP 1 LASTPIN (-2125 2800) BN 3
J 2
(-2113 2808);
DISPLAY 0.680851 (-2113 2808);
PAINT GREEN (-2113 2808);
FORCEPROP 2 LAST CDS_LIB standard
J 0
(-2175 2800);
DISPLAY INVISIBLE (-2175 2800);
FORCEPROP 1 LAST BODY_TYPE PLUMBING
J 2
(-2175 2850);
DISPLAY 0.872340 (-2175 2850);
PAINT GREEN (-2175 2850);
DISPLAY INVISIBLE (-2175 2850);
FORCEPROP 1 LAST HDL_TAP TRUE
J 2
(-2500 2675);
DISPLAY 0.872340 (-2500 2675);
DISPLAY INVISIBLE (-2500 2675);
FORCEPROP 1 LAST PATH I56
J 2
(-2173 2800);
DISPLAY 0.872340 (-2173 2800);
PAINT GREEN (-2173 2800);
DISPLAY INVISIBLE (-2173 2800);
FORCEADD TAP..1
R 2
(-2175 2850);
FORCEPROP 3 LASTPIN (-2125 2850) SIG_NAME M_B_CPU0_SA_CB<4>
J 0
(-2115 2860);
DISPLAY 0.659574 (-2115 2860);
PAINT MONO (-2115 2860);
DISPLAY INVISIBLE (-2115 2860);
FORCEPROP 1 LASTPIN (-2125 2850) BN 4
J 2
(-2113 2858);
DISPLAY 0.680851 (-2113 2858);
PAINT GREEN (-2113 2858);
FORCEPROP 2 LAST CDS_LIB standard
J 0
(-2175 2850);
DISPLAY INVISIBLE (-2175 2850);
FORCEPROP 1 LAST BODY_TYPE PLUMBING
J 2
(-2175 2900);
DISPLAY 0.872340 (-2175 2900);
PAINT GREEN (-2175 2900);
DISPLAY INVISIBLE (-2175 2900);
FORCEPROP 1 LAST HDL_TAP TRUE
J 2
(-2500 2725);
DISPLAY 0.872340 (-2500 2725);
DISPLAY INVISIBLE (-2500 2725);
FORCEPROP 1 LAST PATH I57
J 2
(-2173 2850);
DISPLAY 0.872340 (-2173 2850);
PAINT GREEN (-2173 2850);
DISPLAY INVISIBLE (-2173 2850);
FORCEADD TAP..1
R 2
(-2175 2950);
FORCEPROP 3 LASTPIN (-2125 2950) SIG_NAME M_B_CPU0_SA_CB<6>
J 0
(-2115 2960);
DISPLAY 0.659574 (-2115 2960);
PAINT MONO (-2115 2960);
DISPLAY INVISIBLE (-2115 2960);
FORCEPROP 1 LASTPIN (-2125 2950) BN 6
J 2
(-2113 2958);
DISPLAY 0.680851 (-2113 2958);
PAINT GREEN (-2113 2958);
FORCEPROP 2 LAST CDS_LIB standard
J 0
(-2175 2950);
DISPLAY INVISIBLE (-2175 2950);
FORCEPROP 1 LAST BODY_TYPE PLUMBING
J 2
(-2175 3000);
DISPLAY 0.872340 (-2175 3000);
PAINT GREEN (-2175 3000);
DISPLAY INVISIBLE (-2175 3000);
FORCEPROP 1 LAST HDL_TAP TRUE
J 2
(-2500 2825);
DISPLAY 0.872340 (-2500 2825);
DISPLAY INVISIBLE (-2500 2825);
FORCEPROP 1 LAST PATH I58
J 2
(-2173 2950);
DISPLAY 0.872340 (-2173 2950);
PAINT GREEN (-2173 2950);
DISPLAY INVISIBLE (-2173 2950);
FORCEADD TAP..1
R 2
(-2175 2900);
FORCEPROP 3 LASTPIN (-2125 2900) SIG_NAME M_B_CPU0_SA_CB<5>
J 0
(-2115 2910);
DISPLAY 0.659574 (-2115 2910);
PAINT MONO (-2115 2910);
DISPLAY INVISIBLE (-2115 2910);
FORCEPROP 1 LASTPIN (-2125 2900) BN 5
J 2
(-2113 2908);
DISPLAY 0.680851 (-2113 2908);
PAINT GREEN (-2113 2908);
FORCEPROP 2 LAST CDS_LIB standard
J 0
(-2175 2900);
DISPLAY INVISIBLE (-2175 2900);
FORCEPROP 1 LAST BODY_TYPE PLUMBING
J 2
(-2175 2950);
DISPLAY 0.872340 (-2175 2950);
PAINT GREEN (-2175 2950);
DISPLAY INVISIBLE (-2175 2950);
FORCEPROP 1 LAST HDL_TAP TRUE
J 2
(-2500 2775);
DISPLAY 0.872340 (-2500 2775);
DISPLAY INVISIBLE (-2500 2775);
FORCEPROP 1 LAST PATH I59
J 2
(-2173 2900);
DISPLAY 0.872340 (-2173 2900);
PAINT GREEN (-2173 2900);
DISPLAY INVISIBLE (-2173 2900);
FORCEADD TAP..1
R 2
(-2175 3000);
FORCEPROP 3 LASTPIN (-2125 3000) SIG_NAME M_B_CPU0_SA_CB<7>
J 0
(-2115 3010);
DISPLAY 0.659574 (-2115 3010);
PAINT MONO (-2115 3010);
DISPLAY INVISIBLE (-2115 3010);
FORCEPROP 1 LASTPIN (-2125 3000) BN 7
J 2
(-2113 3008);
DISPLAY 0.680851 (-2113 3008);
PAINT GREEN (-2113 3008);
FORCEPROP 2 LAST CDS_LIB standard
J 0
(-2175 3000);
DISPLAY INVISIBLE (-2175 3000);
FORCEPROP 1 LAST BODY_TYPE PLUMBING
J 2
(-2175 3050);
DISPLAY 0.872340 (-2175 3050);
PAINT GREEN (-2175 3050);
DISPLAY INVISIBLE (-2175 3050);
FORCEPROP 1 LAST HDL_TAP TRUE
J 2
(-2500 2875);
DISPLAY 0.872340 (-2500 2875);
DISPLAY INVISIBLE (-2500 2875);
FORCEPROP 1 LAST PATH I60
J 2
(-2173 3000);
DISPLAY 0.872340 (-2173 3000);
PAINT GREEN (-2173 3000);
DISPLAY INVISIBLE (-2173 3000);
FORCEADD TAP..1
R 2
(-2175 3700);
FORCEPROP 3 LASTPIN (-2125 3700) SIG_NAME M_B_CPU0_SB_CA<0>
J 0
(-2115 3710);
DISPLAY 0.659574 (-2115 3710);
PAINT MONO (-2115 3710);
DISPLAY INVISIBLE (-2115 3710);
FORCEPROP 1 LASTPIN (-2125 3700) BN 0
J 2
(-2113 3708);
DISPLAY 0.680851 (-2113 3708);
PAINT GREEN (-2113 3708);
FORCEPROP 2 LAST CDS_LIB standard
J 0
(-2175 3700);
DISPLAY INVISIBLE (-2175 3700);
FORCEPROP 1 LAST BODY_TYPE PLUMBING
J 2
(-2175 3750);
DISPLAY 0.872340 (-2175 3750);
PAINT GREEN (-2175 3750);
DISPLAY INVISIBLE (-2175 3750);
FORCEPROP 1 LAST HDL_TAP TRUE
J 2
(-2500 3575);
DISPLAY 0.872340 (-2500 3575);
DISPLAY INVISIBLE (-2500 3575);
FORCEPROP 1 LAST PATH I61
J 2
(-2173 3700);
DISPLAY 0.872340 (-2173 3700);
PAINT GREEN (-2173 3700);
DISPLAY INVISIBLE (-2173 3700);
FORCEADD TAP..1
R 2
(-2175 3750);
FORCEPROP 3 LASTPIN (-2125 3750) SIG_NAME M_B_CPU0_SB_CA<1>
J 0
(-2115 3760);
DISPLAY 0.659574 (-2115 3760);
PAINT MONO (-2115 3760);
DISPLAY INVISIBLE (-2115 3760);
FORCEPROP 1 LASTPIN (-2125 3750) BN 1
J 2
(-2113 3758);
DISPLAY 0.680851 (-2113 3758);
PAINT GREEN (-2113 3758);
FORCEPROP 2 LAST CDS_LIB standard
J 0
(-2175 3750);
DISPLAY INVISIBLE (-2175 3750);
FORCEPROP 1 LAST BODY_TYPE PLUMBING
J 2
(-2175 3800);
DISPLAY 0.872340 (-2175 3800);
PAINT GREEN (-2175 3800);
DISPLAY INVISIBLE (-2175 3800);
FORCEPROP 1 LAST HDL_TAP TRUE
J 2
(-2500 3625);
DISPLAY 0.872340 (-2500 3625);
DISPLAY INVISIBLE (-2500 3625);
FORCEPROP 1 LAST PATH I62
J 2
(-2173 3750);
DISPLAY 0.872340 (-2173 3750);
PAINT GREEN (-2173 3750);
DISPLAY INVISIBLE (-2173 3750);
FORCEADD TAP..1
R 2
(-2175 3850);
FORCEPROP 3 LASTPIN (-2125 3850) SIG_NAME M_B_CPU0_SB_CA<3>
J 0
(-2115 3860);
DISPLAY 0.659574 (-2115 3860);
PAINT MONO (-2115 3860);
DISPLAY INVISIBLE (-2115 3860);
FORCEPROP 1 LASTPIN (-2125 3850) BN 3
J 2
(-2113 3858);
DISPLAY 0.680851 (-2113 3858);
PAINT GREEN (-2113 3858);
FORCEPROP 2 LAST CDS_LIB standard
J 0
(-2175 3850);
DISPLAY INVISIBLE (-2175 3850);
FORCEPROP 1 LAST BODY_TYPE PLUMBING
J 2
(-2175 3900);
DISPLAY 0.872340 (-2175 3900);
PAINT GREEN (-2175 3900);
DISPLAY INVISIBLE (-2175 3900);
FORCEPROP 1 LAST HDL_TAP TRUE
J 2
(-2500 3725);
DISPLAY 0.872340 (-2500 3725);
DISPLAY INVISIBLE (-2500 3725);
FORCEPROP 1 LAST PATH I63
J 2
(-2173 3850);
DISPLAY 0.872340 (-2173 3850);
PAINT GREEN (-2173 3850);
DISPLAY INVISIBLE (-2173 3850);
FORCEADD TAP..1
R 2
(-2175 3800);
FORCEPROP 3 LASTPIN (-2125 3800) SIG_NAME M_B_CPU0_SB_CA<2>
J 0
(-2115 3810);
DISPLAY 0.659574 (-2115 3810);
PAINT MONO (-2115 3810);
DISPLAY INVISIBLE (-2115 3810);
FORCEPROP 1 LASTPIN (-2125 3800) BN 2
J 2
(-2113 3808);
DISPLAY 0.680851 (-2113 3808);
PAINT GREEN (-2113 3808);
FORCEPROP 2 LAST CDS_LIB standard
J 0
(-2175 3800);
DISPLAY INVISIBLE (-2175 3800);
FORCEPROP 1 LAST BODY_TYPE PLUMBING
J 2
(-2175 3850);
DISPLAY 0.872340 (-2175 3850);
PAINT GREEN (-2175 3850);
DISPLAY INVISIBLE (-2175 3850);
FORCEPROP 1 LAST HDL_TAP TRUE
J 2
(-2500 3675);
DISPLAY 0.872340 (-2500 3675);
DISPLAY INVISIBLE (-2500 3675);
FORCEPROP 1 LAST PATH I64
J 2
(-2173 3800);
DISPLAY 0.872340 (-2173 3800);
PAINT GREEN (-2173 3800);
DISPLAY INVISIBLE (-2173 3800);
FORCEADD TAP..1
R 2
(-2175 3900);
FORCEPROP 3 LASTPIN (-2125 3900) SIG_NAME M_B_CPU0_SB_CA<4>
J 0
(-2115 3910);
DISPLAY 0.659574 (-2115 3910);
PAINT MONO (-2115 3910);
DISPLAY INVISIBLE (-2115 3910);
FORCEPROP 1 LASTPIN (-2125 3900) BN 4
J 2
(-2113 3908);
DISPLAY 0.680851 (-2113 3908);
PAINT GREEN (-2113 3908);
FORCEPROP 2 LAST CDS_LIB standard
J 0
(-2175 3900);
DISPLAY INVISIBLE (-2175 3900);
FORCEPROP 1 LAST BODY_TYPE PLUMBING
J 2
(-2175 3950);
DISPLAY 0.872340 (-2175 3950);
PAINT GREEN (-2175 3950);
DISPLAY INVISIBLE (-2175 3950);
FORCEPROP 1 LAST HDL_TAP TRUE
J 2
(-2500 3775);
DISPLAY 0.872340 (-2500 3775);
DISPLAY INVISIBLE (-2500 3775);
FORCEPROP 1 LAST PATH I65
J 2
(-2173 3900);
DISPLAY 0.872340 (-2173 3900);
PAINT GREEN (-2173 3900);
DISPLAY INVISIBLE (-2173 3900);
FORCEADD TAP..1
R 2
(-2175 4000);
FORCEPROP 3 LASTPIN (-2125 4000) SIG_NAME M_B_CPU0_SB_CA<6>
J 0
(-2115 4010);
DISPLAY 0.659574 (-2115 4010);
PAINT MONO (-2115 4010);
DISPLAY INVISIBLE (-2115 4010);
FORCEPROP 1 LASTPIN (-2125 4000) BN 6
J 2
(-2113 4008);
DISPLAY 0.680851 (-2113 4008);
PAINT GREEN (-2113 4008);
FORCEPROP 2 LAST CDS_LIB standard
J 0
(-2175 4000);
DISPLAY INVISIBLE (-2175 4000);
FORCEPROP 1 LAST BODY_TYPE PLUMBING
J 2
(-2175 4050);
DISPLAY 0.872340 (-2175 4050);
PAINT GREEN (-2175 4050);
DISPLAY INVISIBLE (-2175 4050);
FORCEPROP 1 LAST HDL_TAP TRUE
J 2
(-2500 3875);
DISPLAY 0.872340 (-2500 3875);
DISPLAY INVISIBLE (-2500 3875);
FORCEPROP 1 LAST PATH I66
J 2
(-2173 4000);
DISPLAY 0.872340 (-2173 4000);
PAINT GREEN (-2173 4000);
DISPLAY INVISIBLE (-2173 4000);
FORCEADD TAP..1
R 2
(-2175 3950);
FORCEPROP 3 LASTPIN (-2125 3950) SIG_NAME M_B_CPU0_SB_CA<5>
J 0
(-2115 3960);
DISPLAY 0.659574 (-2115 3960);
PAINT MONO (-2115 3960);
DISPLAY INVISIBLE (-2115 3960);
FORCEPROP 1 LASTPIN (-2125 3950) BN 5
J 2
(-2113 3958);
DISPLAY 0.680851 (-2113 3958);
PAINT GREEN (-2113 3958);
FORCEPROP 2 LAST CDS_LIB standard
J 0
(-2175 3950);
DISPLAY INVISIBLE (-2175 3950);
FORCEPROP 1 LAST BODY_TYPE PLUMBING
J 2
(-2175 4000);
DISPLAY 0.872340 (-2175 4000);
PAINT GREEN (-2175 4000);
DISPLAY INVISIBLE (-2175 4000);
FORCEPROP 1 LAST HDL_TAP TRUE
J 2
(-2500 3825);
DISPLAY 0.872340 (-2500 3825);
DISPLAY INVISIBLE (-2500 3825);
FORCEPROP 1 LAST PATH I67
J 2
(-2173 3950);
DISPLAY 0.872340 (-2173 3950);
PAINT GREEN (-2173 3950);
DISPLAY INVISIBLE (-2173 3950);
FORCEADD TAP..1
R 2
(-2175 4100);
FORCEPROP 3 LASTPIN (-2125 4100) SIG_NAME M_B_CPU0_SA_CA<0>
J 0
(-2115 4110);
DISPLAY 0.659574 (-2115 4110);
PAINT MONO (-2115 4110);
DISPLAY INVISIBLE (-2115 4110);
FORCEPROP 1 LASTPIN (-2125 4100) BN 0
J 2
(-2113 4108);
DISPLAY 0.680851 (-2113 4108);
PAINT GREEN (-2113 4108);
FORCEPROP 2 LAST CDS_LIB standard
J 0
(-2175 4100);
DISPLAY INVISIBLE (-2175 4100);
FORCEPROP 1 LAST BODY_TYPE PLUMBING
J 2
(-2175 4150);
DISPLAY 0.872340 (-2175 4150);
PAINT GREEN (-2175 4150);
DISPLAY INVISIBLE (-2175 4150);
FORCEPROP 1 LAST HDL_TAP TRUE
J 2
(-2500 3975);
DISPLAY 0.872340 (-2500 3975);
DISPLAY INVISIBLE (-2500 3975);
FORCEPROP 1 LAST PATH I68
J 2
(-2173 4100);
DISPLAY 0.872340 (-2173 4100);
PAINT GREEN (-2173 4100);
DISPLAY INVISIBLE (-2173 4100);
FORCEADD TAP..1
R 2
(-2175 4150);
FORCEPROP 3 LASTPIN (-2125 4150) SIG_NAME M_B_CPU0_SA_CA<1>
J 0
(-2115 4160);
DISPLAY 0.659574 (-2115 4160);
PAINT MONO (-2115 4160);
DISPLAY INVISIBLE (-2115 4160);
FORCEPROP 1 LASTPIN (-2125 4150) BN 1
J 2
(-2113 4158);
DISPLAY 0.680851 (-2113 4158);
PAINT GREEN (-2113 4158);
FORCEPROP 2 LAST CDS_LIB standard
J 0
(-2175 4150);
DISPLAY INVISIBLE (-2175 4150);
FORCEPROP 1 LAST BODY_TYPE PLUMBING
J 2
(-2175 4200);
DISPLAY 0.872340 (-2175 4200);
PAINT GREEN (-2175 4200);
DISPLAY INVISIBLE (-2175 4200);
FORCEPROP 1 LAST HDL_TAP TRUE
J 2
(-2500 4025);
DISPLAY 0.872340 (-2500 4025);
DISPLAY INVISIBLE (-2500 4025);
FORCEPROP 1 LAST PATH I69
J 2
(-2173 4150);
DISPLAY 0.872340 (-2173 4150);
PAINT GREEN (-2173 4150);
DISPLAY INVISIBLE (-2173 4150);
FORCEADD OFFPAGE..1
(-3000 1850);
FORCEPROP 2 LAST $XR7 89 
J 0
(-3522 1814);
DISPLAY 0.638298 (-3522 1814);
PAINT MONO (-3522 1814);
FORCEPROP 2 LAST $XR6 88 
J 0
(-3432 1814);
DISPLAY 0.638298 (-3432 1814);
PAINT MONO (-3432 1814);
FORCEPROP 2 LAST $XR5 87 
J 0
(-3342 1814);
DISPLAY 0.638298 (-3342 1814);
PAINT MONO (-3342 1814);
FORCEPROP 2 LAST $XR4 86 
J 0
(-3252 1814);
DISPLAY 0.638298 (-3252 1814);
PAINT MONO (-3252 1814);
FORCEPROP 2 LAST $XR3 84 
J 0
(-3522 1850);
DISPLAY 0.638298 (-3522 1850);
PAINT MONO (-3522 1850);
FORCEPROP 2 LAST $XR2 83 
J 0
(-3432 1850);
DISPLAY 0.638298 (-3432 1850);
PAINT MONO (-3432 1850);
FORCEPROP 2 LAST $XR1 82 
J 0
(-3342 1850);
DISPLAY 0.638298 (-3342 1850);
PAINT MONO (-3342 1850);
FORCEPROP 2 LAST $XR0 229 
J 0
(-3252 1850);
DISPLAY 0.638298 (-3252 1850);
PAINT MONO (-3252 1850);
FORCEPROP 2 LAST CDS_LIB standard
J 0
(-3000 1850);
PAINT MONO (-3000 1850);
DISPLAY INVISIBLE (-3000 1850);
FORCEPROP 1 LAST OFFPAGE TRUE
J 0
(-2675 1725);
DISPLAY 0.872340 (-2675 1725);
DISPLAY INVISIBLE (-2675 1725);
FORCEPROP 1 LAST COMMENT_BODY TRUE
J 0
(-2875 1750);
DISPLAY 0.872340 (-2875 1750);
PAINT GREEN (-2875 1750);
DISPLAY INVISIBLE (-2875 1750);
FORCEPROP 2 LAST PATH I7
J 0
(-2950 1925);
DISPLAY 1.021277 (-2950 1925);
DISPLAY INVISIBLE (-2950 1925);
FORCEADD TAP..1
R 2
(-2175 4200);
FORCEPROP 3 LASTPIN (-2125 4200) SIG_NAME M_B_CPU0_SA_CA<2>
J 0
(-2115 4210);
DISPLAY 0.659574 (-2115 4210);
PAINT MONO (-2115 4210);
DISPLAY INVISIBLE (-2115 4210);
FORCEPROP 1 LASTPIN (-2125 4200) BN 2
J 2
(-2113 4208);
DISPLAY 0.680851 (-2113 4208);
PAINT GREEN (-2113 4208);
FORCEPROP 2 LAST CDS_LIB standard
J 0
(-2175 4200);
DISPLAY INVISIBLE (-2175 4200);
FORCEPROP 1 LAST BODY_TYPE PLUMBING
J 2
(-2175 4250);
DISPLAY 0.872340 (-2175 4250);
PAINT GREEN (-2175 4250);
DISPLAY INVISIBLE (-2175 4250);
FORCEPROP 1 LAST HDL_TAP TRUE
J 2
(-2500 4075);
DISPLAY 0.872340 (-2500 4075);
DISPLAY INVISIBLE (-2500 4075);
FORCEPROP 1 LAST PATH I70
J 2
(-2173 4200);
DISPLAY 0.872340 (-2173 4200);
PAINT GREEN (-2173 4200);
DISPLAY INVISIBLE (-2173 4200);
FORCEADD TAP..1
R 2
(-2175 4250);
FORCEPROP 3 LASTPIN (-2125 4250) SIG_NAME M_B_CPU0_SA_CA<3>
J 0
(-2115 4260);
DISPLAY 0.659574 (-2115 4260);
PAINT MONO (-2115 4260);
DISPLAY INVISIBLE (-2115 4260);
FORCEPROP 1 LASTPIN (-2125 4250) BN 3
J 2
(-2113 4258);
DISPLAY 0.680851 (-2113 4258);
PAINT GREEN (-2113 4258);
FORCEPROP 2 LAST CDS_LIB standard
J 0
(-2175 4250);
DISPLAY INVISIBLE (-2175 4250);
FORCEPROP 1 LAST BODY_TYPE PLUMBING
J 2
(-2175 4300);
DISPLAY 0.872340 (-2175 4300);
PAINT GREEN (-2175 4300);
DISPLAY INVISIBLE (-2175 4300);
FORCEPROP 1 LAST HDL_TAP TRUE
J 2
(-2500 4125);
DISPLAY 0.872340 (-2500 4125);
DISPLAY INVISIBLE (-2500 4125);
FORCEPROP 1 LAST PATH I71
J 2
(-2173 4250);
DISPLAY 0.872340 (-2173 4250);
PAINT GREEN (-2173 4250);
DISPLAY INVISIBLE (-2173 4250);
FORCEADD TAP..1
(-525 2250);
FORCEPROP 3 LASTPIN (-575 2250) SIG_NAME M_B_CPU0_SB_DQ<21>
J 0
(-565 2260);
DISPLAY 0.659574 (-565 2260);
PAINT MONO (-565 2260);
DISPLAY INVISIBLE (-565 2260);
FORCEPROP 1 LASTPIN (-575 2250) BN 21
J 0
(-587 2258);
DISPLAY 0.680851 (-587 2258);
PAINT GREEN (-587 2258);
FORCEPROP 2 LAST CDS_LIB standard
J 0
(-525 2250);
PAINT MONO (-525 2250);
DISPLAY INVISIBLE (-525 2250);
FORCEPROP 1 LAST BODY_TYPE PLUMBING
J 0
(-525 2300);
DISPLAY 0.872340 (-525 2300);
PAINT GREEN (-525 2300);
DISPLAY INVISIBLE (-525 2300);
FORCEPROP 1 LAST HDL_TAP TRUE
J 0
(-200 2125);
DISPLAY 0.872340 (-200 2125);
DISPLAY INVISIBLE (-200 2125);
FORCEPROP 1 LAST PATH I72
J 0
(-527 2250);
DISPLAY 0.872340 (-527 2250);
PAINT GREEN (-527 2250);
DISPLAY INVISIBLE (-527 2250);
FORCEADD TAP..1
(-525 2300);
FORCEPROP 3 LASTPIN (-575 2300) SIG_NAME M_B_CPU0_SB_DQ<22>
J 0
(-565 2310);
DISPLAY 0.659574 (-565 2310);
PAINT MONO (-565 2310);
DISPLAY INVISIBLE (-565 2310);
FORCEPROP 1 LASTPIN (-575 2300) BN 22
J 0
(-587 2308);
DISPLAY 0.680851 (-587 2308);
PAINT GREEN (-587 2308);
FORCEPROP 2 LAST CDS_LIB standard
J 0
(-525 2300);
DISPLAY INVISIBLE (-525 2300);
FORCEPROP 1 LAST BODY_TYPE PLUMBING
J 0
(-525 2350);
DISPLAY 0.872340 (-525 2350);
PAINT GREEN (-525 2350);
DISPLAY INVISIBLE (-525 2350);
FORCEPROP 1 LAST HDL_TAP TRUE
J 0
(-200 2175);
DISPLAY 0.872340 (-200 2175);
DISPLAY INVISIBLE (-200 2175);
FORCEPROP 1 LAST PATH I73
J 0
(-527 2300);
DISPLAY 0.872340 (-527 2300);
PAINT GREEN (-527 2300);
DISPLAY INVISIBLE (-527 2300);
FORCEADD TAP..1
(-525 2350);
FORCEPROP 3 LASTPIN (-575 2350) SIG_NAME M_B_CPU0_SB_DQ<23>
J 0
(-565 2360);
DISPLAY 0.659574 (-565 2360);
PAINT MONO (-565 2360);
DISPLAY INVISIBLE (-565 2360);
FORCEPROP 1 LASTPIN (-575 2350) BN 23
J 0
(-587 2358);
DISPLAY 0.680851 (-587 2358);
PAINT GREEN (-587 2358);
FORCEPROP 2 LAST CDS_LIB standard
J 0
(-525 2350);
DISPLAY INVISIBLE (-525 2350);
FORCEPROP 1 LAST BODY_TYPE PLUMBING
J 0
(-525 2400);
DISPLAY 0.872340 (-525 2400);
PAINT GREEN (-525 2400);
DISPLAY INVISIBLE (-525 2400);
FORCEPROP 1 LAST HDL_TAP TRUE
J 0
(-200 2225);
DISPLAY 0.872340 (-200 2225);
DISPLAY INVISIBLE (-200 2225);
FORCEPROP 1 LAST PATH I74
J 0
(-527 2350);
DISPLAY 0.872340 (-527 2350);
PAINT GREEN (-527 2350);
DISPLAY INVISIBLE (-527 2350);
FORCEADD TAP..1
(-525 2400);
FORCEPROP 3 LASTPIN (-575 2400) SIG_NAME M_B_CPU0_SB_DQ<24>
J 0
(-565 2410);
DISPLAY 0.659574 (-565 2410);
PAINT MONO (-565 2410);
DISPLAY INVISIBLE (-565 2410);
FORCEPROP 1 LASTPIN (-575 2400) BN 24
J 0
(-587 2408);
DISPLAY 0.680851 (-587 2408);
PAINT GREEN (-587 2408);
FORCEPROP 2 LAST CDS_LIB standard
J 0
(-525 2400);
DISPLAY INVISIBLE (-525 2400);
FORCEPROP 1 LAST BODY_TYPE PLUMBING
J 0
(-525 2450);
DISPLAY 0.872340 (-525 2450);
PAINT GREEN (-525 2450);
DISPLAY INVISIBLE (-525 2450);
FORCEPROP 1 LAST HDL_TAP TRUE
J 0
(-200 2275);
DISPLAY 0.872340 (-200 2275);
DISPLAY INVISIBLE (-200 2275);
FORCEPROP 1 LAST PATH I75
J 0
(-527 2400);
DISPLAY 0.872340 (-527 2400);
PAINT GREEN (-527 2400);
DISPLAY INVISIBLE (-527 2400);
FORCEADD TAP..1
(-525 2500);
FORCEPROP 3 LASTPIN (-575 2500) SIG_NAME M_B_CPU0_SB_DQ<26>
J 0
(-565 2510);
DISPLAY 0.659574 (-565 2510);
PAINT MONO (-565 2510);
DISPLAY INVISIBLE (-565 2510);
FORCEPROP 1 LASTPIN (-575 2500) BN 26
J 0
(-587 2508);
DISPLAY 0.680851 (-587 2508);
PAINT GREEN (-587 2508);
FORCEPROP 2 LAST CDS_LIB standard
J 0
(-525 2500);
DISPLAY INVISIBLE (-525 2500);
FORCEPROP 1 LAST BODY_TYPE PLUMBING
J 0
(-525 2550);
DISPLAY 0.872340 (-525 2550);
PAINT GREEN (-525 2550);
DISPLAY INVISIBLE (-525 2550);
FORCEPROP 1 LAST HDL_TAP TRUE
J 0
(-200 2375);
DISPLAY 0.872340 (-200 2375);
DISPLAY INVISIBLE (-200 2375);
FORCEPROP 1 LAST PATH I76
J 0
(-527 2500);
DISPLAY 0.872340 (-527 2500);
PAINT GREEN (-527 2500);
DISPLAY INVISIBLE (-527 2500);
FORCEADD TAP..1
(-525 2450);
FORCEPROP 3 LASTPIN (-575 2450) SIG_NAME M_B_CPU0_SB_DQ<25>
J 0
(-565 2460);
DISPLAY 0.659574 (-565 2460);
PAINT MONO (-565 2460);
DISPLAY INVISIBLE (-565 2460);
FORCEPROP 1 LASTPIN (-575 2450) BN 25
J 0
(-587 2458);
DISPLAY 0.680851 (-587 2458);
PAINT GREEN (-587 2458);
FORCEPROP 2 LAST CDS_LIB standard
J 0
(-525 2450);
DISPLAY INVISIBLE (-525 2450);
FORCEPROP 1 LAST BODY_TYPE PLUMBING
J 0
(-525 2500);
DISPLAY 0.872340 (-525 2500);
PAINT GREEN (-525 2500);
DISPLAY INVISIBLE (-525 2500);
FORCEPROP 1 LAST HDL_TAP TRUE
J 0
(-200 2325);
DISPLAY 0.872340 (-200 2325);
DISPLAY INVISIBLE (-200 2325);
FORCEPROP 1 LAST PATH I77
J 0
(-527 2450);
DISPLAY 0.872340 (-527 2450);
PAINT GREEN (-527 2450);
DISPLAY INVISIBLE (-527 2450);
FORCEADD TAP..1
(-525 2550);
FORCEPROP 3 LASTPIN (-575 2550) SIG_NAME M_B_CPU0_SB_DQ<27>
J 0
(-565 2560);
DISPLAY 0.659574 (-565 2560);
PAINT MONO (-565 2560);
DISPLAY INVISIBLE (-565 2560);
FORCEPROP 1 LASTPIN (-575 2550) BN 27
J 0
(-587 2558);
DISPLAY 0.680851 (-587 2558);
PAINT GREEN (-587 2558);
FORCEPROP 2 LAST CDS_LIB standard
J 0
(-525 2550);
DISPLAY INVISIBLE (-525 2550);
FORCEPROP 1 LAST BODY_TYPE PLUMBING
J 0
(-525 2600);
DISPLAY 0.872340 (-525 2600);
PAINT GREEN (-525 2600);
DISPLAY INVISIBLE (-525 2600);
FORCEPROP 1 LAST HDL_TAP TRUE
J 0
(-200 2425);
DISPLAY 0.872340 (-200 2425);
DISPLAY INVISIBLE (-200 2425);
FORCEPROP 1 LAST PATH I78
J 0
(-527 2550);
DISPLAY 0.872340 (-527 2550);
PAINT GREEN (-527 2550);
DISPLAY INVISIBLE (-527 2550);
FORCEADD TAP..1
(-525 2600);
FORCEPROP 3 LASTPIN (-575 2600) SIG_NAME M_B_CPU0_SB_DQ<28>
J 0
(-565 2610);
DISPLAY 0.659574 (-565 2610);
PAINT MONO (-565 2610);
DISPLAY INVISIBLE (-565 2610);
FORCEPROP 1 LASTPIN (-575 2600) BN 28
J 0
(-587 2608);
DISPLAY 0.680851 (-587 2608);
PAINT GREEN (-587 2608);
FORCEPROP 2 LAST CDS_LIB standard
J 0
(-525 2600);
DISPLAY INVISIBLE (-525 2600);
FORCEPROP 1 LAST BODY_TYPE PLUMBING
J 0
(-525 2650);
DISPLAY 0.872340 (-525 2650);
PAINT GREEN (-525 2650);
DISPLAY INVISIBLE (-525 2650);
FORCEPROP 1 LAST HDL_TAP TRUE
J 0
(-200 2475);
DISPLAY 0.872340 (-200 2475);
DISPLAY INVISIBLE (-200 2475);
FORCEPROP 1 LAST PATH I79
J 0
(-527 2600);
DISPLAY 0.872340 (-527 2600);
PAINT GREEN (-527 2600);
DISPLAY INVISIBLE (-527 2600);
FORCEADD OFFPAGE..1
(-3000 1900);
FORCEPROP 2 LAST $XR0 85 
J 0
(-3221 1900);
DISPLAY 0.638298 (-3221 1900);
PAINT MONO (-3221 1900);
FORCEPROP 2 LAST CDS_LIB standard
J 0
(-3000 1900);
PAINT MONO (-3000 1900);
DISPLAY INVISIBLE (-3000 1900);
FORCEPROP 1 LAST OFFPAGE TRUE
J 0
(-2675 1775);
DISPLAY 0.872340 (-2675 1775);
DISPLAY INVISIBLE (-2675 1775);
FORCEPROP 1 LAST COMMENT_BODY TRUE
J 0
(-2875 1800);
DISPLAY 0.872340 (-2875 1800);
PAINT GREEN (-2875 1800);
DISPLAY INVISIBLE (-2875 1800);
FORCEPROP 2 LAST PATH I8
J 0
(-2950 1975);
DISPLAY 1.021277 (-2950 1975);
DISPLAY INVISIBLE (-2950 1975);
FORCEADD TAP..1
(-525 2650);
FORCEPROP 3 LASTPIN (-575 2650) SIG_NAME M_B_CPU0_SB_DQ<29>
J 0
(-565 2660);
DISPLAY 0.659574 (-565 2660);
PAINT MONO (-565 2660);
DISPLAY INVISIBLE (-565 2660);
FORCEPROP 1 LASTPIN (-575 2650) BN 29
J 0
(-587 2658);
DISPLAY 0.680851 (-587 2658);
PAINT GREEN (-587 2658);
FORCEPROP 2 LAST CDS_LIB standard
J 0
(-525 2650);
DISPLAY INVISIBLE (-525 2650);
FORCEPROP 1 LAST BODY_TYPE PLUMBING
J 0
(-525 2700);
DISPLAY 0.872340 (-525 2700);
PAINT GREEN (-525 2700);
DISPLAY INVISIBLE (-525 2700);
FORCEPROP 1 LAST HDL_TAP TRUE
J 0
(-200 2525);
DISPLAY 0.872340 (-200 2525);
DISPLAY INVISIBLE (-200 2525);
FORCEPROP 1 LAST PATH I80
J 0
(-527 2650);
DISPLAY 0.872340 (-527 2650);
PAINT GREEN (-527 2650);
DISPLAY INVISIBLE (-527 2650);
FORCEADD TAP..1
(-525 2750);
FORCEPROP 3 LASTPIN (-575 2750) SIG_NAME M_B_CPU0_SB_DQ<31>
J 0
(-565 2760);
DISPLAY 0.659574 (-565 2760);
PAINT MONO (-565 2760);
DISPLAY INVISIBLE (-565 2760);
FORCEPROP 1 LASTPIN (-575 2750) BN 31
J 0
(-587 2758);
DISPLAY 0.680851 (-587 2758);
PAINT GREEN (-587 2758);
FORCEPROP 2 LAST CDS_LIB standard
J 0
(-525 2750);
DISPLAY INVISIBLE (-525 2750);
FORCEPROP 1 LAST BODY_TYPE PLUMBING
J 0
(-525 2800);
DISPLAY 0.872340 (-525 2800);
PAINT GREEN (-525 2800);
DISPLAY INVISIBLE (-525 2800);
FORCEPROP 1 LAST HDL_TAP TRUE
J 0
(-200 2625);
DISPLAY 0.872340 (-200 2625);
DISPLAY INVISIBLE (-200 2625);
FORCEPROP 1 LAST PATH I81
J 0
(-527 2750);
DISPLAY 0.872340 (-527 2750);
PAINT GREEN (-527 2750);
DISPLAY INVISIBLE (-527 2750);
FORCEADD TAP..1
(-525 2700);
FORCEPROP 3 LASTPIN (-575 2700) SIG_NAME M_B_CPU0_SB_DQ<30>
J 0
(-565 2710);
DISPLAY 0.659574 (-565 2710);
PAINT MONO (-565 2710);
DISPLAY INVISIBLE (-565 2710);
FORCEPROP 1 LASTPIN (-575 2700) BN 30
J 0
(-587 2708);
DISPLAY 0.680851 (-587 2708);
PAINT GREEN (-587 2708);
FORCEPROP 2 LAST CDS_LIB standard
J 0
(-525 2700);
DISPLAY INVISIBLE (-525 2700);
FORCEPROP 1 LAST BODY_TYPE PLUMBING
J 0
(-525 2750);
DISPLAY 0.872340 (-525 2750);
PAINT GREEN (-525 2750);
DISPLAY INVISIBLE (-525 2750);
FORCEPROP 1 LAST HDL_TAP TRUE
J 0
(-200 2575);
DISPLAY 0.872340 (-200 2575);
DISPLAY INVISIBLE (-200 2575);
FORCEPROP 1 LAST PATH I82
J 0
(-527 2700);
DISPLAY 0.872340 (-527 2700);
PAINT GREEN (-527 2700);
DISPLAY INVISIBLE (-527 2700);
FORCEADD TAP..1
(-525 2850);
FORCEPROP 3 LASTPIN (-575 2850) SIG_NAME M_B_CPU0_SA_DQ<0>
J 0
(-565 2860);
DISPLAY 0.659574 (-565 2860);
PAINT MONO (-565 2860);
DISPLAY INVISIBLE (-565 2860);
FORCEPROP 1 LASTPIN (-575 2850) BN 0
J 0
(-587 2858);
DISPLAY 0.680851 (-587 2858);
PAINT GREEN (-587 2858);
FORCEPROP 2 LAST CDS_LIB standard
J 0
(-525 2850);
PAINT MONO (-525 2850);
DISPLAY INVISIBLE (-525 2850);
FORCEPROP 1 LAST BODY_TYPE PLUMBING
J 0
(-525 2900);
DISPLAY 0.872340 (-525 2900);
PAINT GREEN (-525 2900);
DISPLAY INVISIBLE (-525 2900);
FORCEPROP 1 LAST HDL_TAP TRUE
J 0
(-200 2725);
DISPLAY 0.872340 (-200 2725);
DISPLAY INVISIBLE (-200 2725);
FORCEPROP 1 LAST PATH I83
J 0
(-527 2850);
DISPLAY 0.872340 (-527 2850);
PAINT GREEN (-527 2850);
DISPLAY INVISIBLE (-527 2850);
FORCEADD TAP..1
(-525 2900);
FORCEPROP 3 LASTPIN (-575 2900) SIG_NAME M_B_CPU0_SA_DQ<1>
J 0
(-565 2910);
DISPLAY 0.659574 (-565 2910);
PAINT MONO (-565 2910);
DISPLAY INVISIBLE (-565 2910);
FORCEPROP 1 LASTPIN (-575 2900) BN 1
J 0
(-587 2908);
DISPLAY 0.680851 (-587 2908);
PAINT GREEN (-587 2908);
FORCEPROP 2 LAST CDS_LIB standard
J 0
(-525 2900);
PAINT MONO (-525 2900);
DISPLAY INVISIBLE (-525 2900);
FORCEPROP 1 LAST BODY_TYPE PLUMBING
J 0
(-525 2950);
DISPLAY 0.872340 (-525 2950);
PAINT GREEN (-525 2950);
DISPLAY INVISIBLE (-525 2950);
FORCEPROP 1 LAST HDL_TAP TRUE
J 0
(-200 2775);
DISPLAY 0.872340 (-200 2775);
DISPLAY INVISIBLE (-200 2775);
FORCEPROP 1 LAST PATH I84
J 0
(-527 2900);
DISPLAY 0.872340 (-527 2900);
PAINT GREEN (-527 2900);
DISPLAY INVISIBLE (-527 2900);
FORCEADD TAP..1
(-525 2950);
FORCEPROP 3 LASTPIN (-575 2950) SIG_NAME M_B_CPU0_SA_DQ<2>
J 0
(-565 2960);
DISPLAY 0.659574 (-565 2960);
PAINT MONO (-565 2960);
DISPLAY INVISIBLE (-565 2960);
FORCEPROP 1 LASTPIN (-575 2950) BN 2
J 0
(-587 2958);
DISPLAY 0.680851 (-587 2958);
PAINT GREEN (-587 2958);
FORCEPROP 2 LAST CDS_LIB standard
J 0
(-525 2950);
PAINT MONO (-525 2950);
DISPLAY INVISIBLE (-525 2950);
FORCEPROP 1 LAST BODY_TYPE PLUMBING
J 0
(-525 3000);
DISPLAY 0.872340 (-525 3000);
PAINT GREEN (-525 3000);
DISPLAY INVISIBLE (-525 3000);
FORCEPROP 1 LAST HDL_TAP TRUE
J 0
(-200 2825);
DISPLAY 0.872340 (-200 2825);
DISPLAY INVISIBLE (-200 2825);
FORCEPROP 1 LAST PATH I85
J 0
(-527 2950);
DISPLAY 0.872340 (-527 2950);
PAINT GREEN (-527 2950);
DISPLAY INVISIBLE (-527 2950);
FORCEADD TAP..1
(-525 3000);
FORCEPROP 3 LASTPIN (-575 3000) SIG_NAME M_B_CPU0_SA_DQ<3>
J 0
(-565 3010);
DISPLAY 0.659574 (-565 3010);
PAINT MONO (-565 3010);
DISPLAY INVISIBLE (-565 3010);
FORCEPROP 1 LASTPIN (-575 3000) BN 3
J 0
(-587 3008);
DISPLAY 0.680851 (-587 3008);
PAINT GREEN (-587 3008);
FORCEPROP 2 LAST CDS_LIB standard
J 0
(-525 3000);
PAINT MONO (-525 3000);
DISPLAY INVISIBLE (-525 3000);
FORCEPROP 1 LAST BODY_TYPE PLUMBING
J 0
(-525 3050);
DISPLAY 0.872340 (-525 3050);
PAINT GREEN (-525 3050);
DISPLAY INVISIBLE (-525 3050);
FORCEPROP 1 LAST HDL_TAP TRUE
J 0
(-200 2875);
DISPLAY 0.872340 (-200 2875);
DISPLAY INVISIBLE (-200 2875);
FORCEPROP 1 LAST PATH I86
J 0
(-527 3000);
DISPLAY 0.872340 (-527 3000);
PAINT GREEN (-527 3000);
DISPLAY INVISIBLE (-527 3000);
FORCEADD TAP..1
(-525 3050);
FORCEPROP 3 LASTPIN (-575 3050) SIG_NAME M_B_CPU0_SA_DQ<4>
J 0
(-565 3060);
DISPLAY 0.659574 (-565 3060);
PAINT MONO (-565 3060);
DISPLAY INVISIBLE (-565 3060);
FORCEPROP 1 LASTPIN (-575 3050) BN 4
J 0
(-587 3058);
DISPLAY 0.680851 (-587 3058);
PAINT GREEN (-587 3058);
FORCEPROP 2 LAST CDS_LIB standard
J 0
(-525 3050);
PAINT MONO (-525 3050);
DISPLAY INVISIBLE (-525 3050);
FORCEPROP 1 LAST BODY_TYPE PLUMBING
J 0
(-525 3100);
DISPLAY 0.872340 (-525 3100);
PAINT GREEN (-525 3100);
DISPLAY INVISIBLE (-525 3100);
FORCEPROP 1 LAST HDL_TAP TRUE
J 0
(-200 2925);
DISPLAY 0.872340 (-200 2925);
DISPLAY INVISIBLE (-200 2925);
FORCEPROP 1 LAST PATH I87
J 0
(-527 3050);
DISPLAY 0.872340 (-527 3050);
PAINT GREEN (-527 3050);
DISPLAY INVISIBLE (-527 3050);
FORCEADD TAP..1
(-525 3100);
FORCEPROP 3 LASTPIN (-575 3100) SIG_NAME M_B_CPU0_SA_DQ<5>
J 0
(-565 3110);
DISPLAY 0.659574 (-565 3110);
PAINT MONO (-565 3110);
DISPLAY INVISIBLE (-565 3110);
FORCEPROP 1 LASTPIN (-575 3100) BN 5
J 0
(-587 3108);
DISPLAY 0.680851 (-587 3108);
PAINT GREEN (-587 3108);
FORCEPROP 2 LAST CDS_LIB standard
J 0
(-525 3100);
PAINT MONO (-525 3100);
DISPLAY INVISIBLE (-525 3100);
FORCEPROP 1 LAST BODY_TYPE PLUMBING
J 0
(-525 3150);
DISPLAY 0.872340 (-525 3150);
PAINT GREEN (-525 3150);
DISPLAY INVISIBLE (-525 3150);
FORCEPROP 1 LAST HDL_TAP TRUE
J 0
(-200 2975);
DISPLAY 0.872340 (-200 2975);
DISPLAY INVISIBLE (-200 2975);
FORCEPROP 1 LAST PATH I88
J 0
(-527 3100);
DISPLAY 0.872340 (-527 3100);
PAINT GREEN (-527 3100);
DISPLAY INVISIBLE (-527 3100);
FORCEADD TAP..1
(-525 3150);
FORCEPROP 3 LASTPIN (-575 3150) SIG_NAME M_B_CPU0_SA_DQ<6>
J 0
(-565 3160);
DISPLAY 0.659574 (-565 3160);
PAINT MONO (-565 3160);
DISPLAY INVISIBLE (-565 3160);
FORCEPROP 1 LASTPIN (-575 3150) BN 6
J 0
(-587 3158);
DISPLAY 0.680851 (-587 3158);
PAINT GREEN (-587 3158);
FORCEPROP 2 LAST CDS_LIB standard
J 0
(-525 3150);
PAINT MONO (-525 3150);
DISPLAY INVISIBLE (-525 3150);
FORCEPROP 1 LAST BODY_TYPE PLUMBING
J 0
(-525 3200);
DISPLAY 0.872340 (-525 3200);
PAINT GREEN (-525 3200);
DISPLAY INVISIBLE (-525 3200);
FORCEPROP 1 LAST HDL_TAP TRUE
J 0
(-200 3025);
DISPLAY 0.872340 (-200 3025);
DISPLAY INVISIBLE (-200 3025);
FORCEPROP 1 LAST PATH I89
J 0
(-527 3150);
DISPLAY 0.872340 (-527 3150);
PAINT GREEN (-527 3150);
DISPLAY INVISIBLE (-527 3150);
FORCEADD OFFPAGE..1
(-3100 2050);
FORCEPROP 2 LAST $XR1 84 
J 0
(-3411 2050);
DISPLAY 0.638298 (-3411 2050);
PAINT MONO (-3411 2050);
FORCEPROP 2 LAST $XR0 21 
J 0
(-3321 2050);
DISPLAY 0.638298 (-3321 2050);
PAINT MONO (-3321 2050);
FORCEPROP 2 LAST CDS_LIB standard
J 0
(-3100 2050);
PAINT MONO (-3100 2050);
DISPLAY INVISIBLE (-3100 2050);
FORCEPROP 1 LAST OFFPAGE TRUE
J 0
(-2775 1925);
DISPLAY 0.872340 (-2775 1925);
DISPLAY INVISIBLE (-2775 1925);
FORCEPROP 1 LAST COMMENT_BODY TRUE
J 0
(-2975 1950);
DISPLAY 0.872340 (-2975 1950);
PAINT GREEN (-2975 1950);
DISPLAY INVISIBLE (-2975 1950);
FORCEPROP 2 LAST PATH I9
J 0
(-3050 2125);
DISPLAY 1.021277 (-3050 2125);
DISPLAY INVISIBLE (-3050 2125);
FORCEADD TAP..1
(-525 3200);
FORCEPROP 3 LASTPIN (-575 3200) SIG_NAME M_B_CPU0_SA_DQ<7>
J 0
(-565 3210);
DISPLAY 0.659574 (-565 3210);
PAINT MONO (-565 3210);
DISPLAY INVISIBLE (-565 3210);
FORCEPROP 1 LASTPIN (-575 3200) BN 7
J 0
(-587 3208);
DISPLAY 0.680851 (-587 3208);
PAINT GREEN (-587 3208);
FORCEPROP 2 LAST CDS_LIB standard
J 0
(-525 3200);
PAINT MONO (-525 3200);
DISPLAY INVISIBLE (-525 3200);
FORCEPROP 1 LAST BODY_TYPE PLUMBING
J 0
(-525 3250);
DISPLAY 0.872340 (-525 3250);
PAINT GREEN (-525 3250);
DISPLAY INVISIBLE (-525 3250);
FORCEPROP 1 LAST HDL_TAP TRUE
J 0
(-200 3075);
DISPLAY 0.872340 (-200 3075);
DISPLAY INVISIBLE (-200 3075);
FORCEPROP 1 LAST PATH I90
J 0
(-527 3200);
DISPLAY 0.872340 (-527 3200);
PAINT GREEN (-527 3200);
DISPLAY INVISIBLE (-527 3200);
FORCEADD TAP..1
(-525 3250);
FORCEPROP 3 LASTPIN (-575 3250) SIG_NAME M_B_CPU0_SA_DQ<8>
J 0
(-565 3260);
DISPLAY 0.659574 (-565 3260);
PAINT MONO (-565 3260);
DISPLAY INVISIBLE (-565 3260);
FORCEPROP 1 LASTPIN (-575 3250) BN 8
J 0
(-587 3258);
DISPLAY 0.680851 (-587 3258);
PAINT GREEN (-587 3258);
FORCEPROP 2 LAST CDS_LIB standard
J 0
(-525 3250);
PAINT MONO (-525 3250);
DISPLAY INVISIBLE (-525 3250);
FORCEPROP 1 LAST BODY_TYPE PLUMBING
J 0
(-525 3300);
DISPLAY 0.872340 (-525 3300);
PAINT GREEN (-525 3300);
DISPLAY INVISIBLE (-525 3300);
FORCEPROP 1 LAST HDL_TAP TRUE
J 0
(-200 3125);
DISPLAY 0.872340 (-200 3125);
DISPLAY INVISIBLE (-200 3125);
FORCEPROP 1 LAST PATH I91
J 0
(-527 3250);
DISPLAY 0.872340 (-527 3250);
PAINT GREEN (-527 3250);
DISPLAY INVISIBLE (-527 3250);
FORCEADD TAP..1
(-525 3350);
FORCEPROP 3 LASTPIN (-575 3350) SIG_NAME M_B_CPU0_SA_DQ<10>
J 0
(-565 3360);
DISPLAY 0.659574 (-565 3360);
PAINT MONO (-565 3360);
DISPLAY INVISIBLE (-565 3360);
FORCEPROP 1 LASTPIN (-575 3350) BN 10
J 0
(-587 3358);
DISPLAY 0.680851 (-587 3358);
PAINT GREEN (-587 3358);
FORCEPROP 2 LAST CDS_LIB standard
J 0
(-525 3350);
PAINT MONO (-525 3350);
DISPLAY INVISIBLE (-525 3350);
FORCEPROP 1 LAST BODY_TYPE PLUMBING
J 0
(-525 3400);
DISPLAY 0.872340 (-525 3400);
PAINT GREEN (-525 3400);
DISPLAY INVISIBLE (-525 3400);
FORCEPROP 1 LAST HDL_TAP TRUE
J 0
(-200 3225);
DISPLAY 0.872340 (-200 3225);
DISPLAY INVISIBLE (-200 3225);
FORCEPROP 1 LAST PATH I92
J 0
(-527 3350);
DISPLAY 0.872340 (-527 3350);
PAINT GREEN (-527 3350);
DISPLAY INVISIBLE (-527 3350);
FORCEADD TAP..1
(-525 3300);
FORCEPROP 3 LASTPIN (-575 3300) SIG_NAME M_B_CPU0_SA_DQ<9>
J 0
(-565 3310);
DISPLAY 0.659574 (-565 3310);
PAINT MONO (-565 3310);
DISPLAY INVISIBLE (-565 3310);
FORCEPROP 1 LASTPIN (-575 3300) BN 9
J 0
(-587 3308);
DISPLAY 0.680851 (-587 3308);
PAINT GREEN (-587 3308);
FORCEPROP 2 LAST CDS_LIB standard
J 0
(-525 3300);
PAINT MONO (-525 3300);
DISPLAY INVISIBLE (-525 3300);
FORCEPROP 1 LAST BODY_TYPE PLUMBING
J 0
(-525 3350);
DISPLAY 0.872340 (-525 3350);
PAINT GREEN (-525 3350);
DISPLAY INVISIBLE (-525 3350);
FORCEPROP 1 LAST HDL_TAP TRUE
J 0
(-200 3175);
DISPLAY 0.872340 (-200 3175);
DISPLAY INVISIBLE (-200 3175);
FORCEPROP 1 LAST PATH I93
J 0
(-527 3300);
DISPLAY 0.872340 (-527 3300);
PAINT GREEN (-527 3300);
DISPLAY INVISIBLE (-527 3300);
FORCEADD TAP..1
(-525 3400);
FORCEPROP 3 LASTPIN (-575 3400) SIG_NAME M_B_CPU0_SA_DQ<11>
J 0
(-565 3410);
DISPLAY 0.659574 (-565 3410);
PAINT MONO (-565 3410);
DISPLAY INVISIBLE (-565 3410);
FORCEPROP 1 LASTPIN (-575 3400) BN 11
J 0
(-587 3408);
DISPLAY 0.680851 (-587 3408);
PAINT GREEN (-587 3408);
FORCEPROP 2 LAST CDS_LIB standard
J 0
(-525 3400);
PAINT MONO (-525 3400);
DISPLAY INVISIBLE (-525 3400);
FORCEPROP 1 LAST BODY_TYPE PLUMBING
J 0
(-525 3450);
DISPLAY 0.872340 (-525 3450);
PAINT GREEN (-525 3450);
DISPLAY INVISIBLE (-525 3450);
FORCEPROP 1 LAST HDL_TAP TRUE
J 0
(-200 3275);
DISPLAY 0.872340 (-200 3275);
DISPLAY INVISIBLE (-200 3275);
FORCEPROP 1 LAST PATH I94
J 0
(-527 3400);
DISPLAY 0.872340 (-527 3400);
PAINT GREEN (-527 3400);
DISPLAY INVISIBLE (-527 3400);
FORCEADD TAP..1
(-525 3450);
FORCEPROP 3 LASTPIN (-575 3450) SIG_NAME M_B_CPU0_SA_DQ<12>
J 0
(-565 3460);
DISPLAY 0.659574 (-565 3460);
PAINT MONO (-565 3460);
DISPLAY INVISIBLE (-565 3460);
FORCEPROP 1 LASTPIN (-575 3450) BN 12
J 0
(-587 3458);
DISPLAY 0.680851 (-587 3458);
PAINT GREEN (-587 3458);
FORCEPROP 2 LAST CDS_LIB standard
J 0
(-525 3450);
PAINT MONO (-525 3450);
DISPLAY INVISIBLE (-525 3450);
FORCEPROP 1 LAST BODY_TYPE PLUMBING
J 0
(-525 3500);
DISPLAY 0.872340 (-525 3500);
PAINT GREEN (-525 3500);
DISPLAY INVISIBLE (-525 3500);
FORCEPROP 1 LAST HDL_TAP TRUE
J 0
(-200 3325);
DISPLAY 0.872340 (-200 3325);
DISPLAY INVISIBLE (-200 3325);
FORCEPROP 1 LAST PATH I95
J 0
(-527 3450);
DISPLAY 0.872340 (-527 3450);
PAINT GREEN (-527 3450);
DISPLAY INVISIBLE (-527 3450);
FORCEADD TAP..1
(-525 3500);
FORCEPROP 3 LASTPIN (-575 3500) SIG_NAME M_B_CPU0_SA_DQ<13>
J 0
(-565 3510);
DISPLAY 0.659574 (-565 3510);
PAINT MONO (-565 3510);
DISPLAY INVISIBLE (-565 3510);
FORCEPROP 1 LASTPIN (-575 3500) BN 13
J 0
(-587 3508);
DISPLAY 0.680851 (-587 3508);
PAINT GREEN (-587 3508);
FORCEPROP 2 LAST CDS_LIB standard
J 0
(-525 3500);
PAINT MONO (-525 3500);
DISPLAY INVISIBLE (-525 3500);
FORCEPROP 1 LAST BODY_TYPE PLUMBING
J 0
(-525 3550);
DISPLAY 0.872340 (-525 3550);
PAINT GREEN (-525 3550);
DISPLAY INVISIBLE (-525 3550);
FORCEPROP 1 LAST HDL_TAP TRUE
J 0
(-200 3375);
DISPLAY 0.872340 (-200 3375);
DISPLAY INVISIBLE (-200 3375);
FORCEPROP 1 LAST PATH I96
J 0
(-527 3500);
DISPLAY 0.872340 (-527 3500);
PAINT GREEN (-527 3500);
DISPLAY INVISIBLE (-527 3500);
FORCEADD TAP..1
(-525 3550);
FORCEPROP 3 LASTPIN (-575 3550) SIG_NAME M_B_CPU0_SA_DQ<14>
J 0
(-565 3560);
DISPLAY 0.659574 (-565 3560);
PAINT MONO (-565 3560);
DISPLAY INVISIBLE (-565 3560);
FORCEPROP 1 LASTPIN (-575 3550) BN 14
J 0
(-587 3558);
DISPLAY 0.680851 (-587 3558);
PAINT GREEN (-587 3558);
FORCEPROP 2 LAST CDS_LIB standard
J 0
(-525 3550);
PAINT MONO (-525 3550);
DISPLAY INVISIBLE (-525 3550);
FORCEPROP 1 LAST BODY_TYPE PLUMBING
J 0
(-525 3600);
DISPLAY 0.872340 (-525 3600);
PAINT GREEN (-525 3600);
DISPLAY INVISIBLE (-525 3600);
FORCEPROP 1 LAST HDL_TAP TRUE
J 0
(-200 3425);
DISPLAY 0.872340 (-200 3425);
DISPLAY INVISIBLE (-200 3425);
FORCEPROP 1 LAST PATH I97
J 0
(-527 3550);
DISPLAY 0.872340 (-527 3550);
PAINT GREEN (-527 3550);
DISPLAY INVISIBLE (-527 3550);
FORCEADD TAP..1
(-525 3650);
FORCEPROP 3 LASTPIN (-575 3650) SIG_NAME M_B_CPU0_SA_DQ<16>
J 0
(-565 3660);
DISPLAY 0.659574 (-565 3660);
PAINT MONO (-565 3660);
DISPLAY INVISIBLE (-565 3660);
FORCEPROP 1 LASTPIN (-575 3650) BN 16
J 0
(-587 3658);
DISPLAY 0.680851 (-587 3658);
PAINT GREEN (-587 3658);
FORCEPROP 2 LAST CDS_LIB standard
J 0
(-525 3650);
PAINT MONO (-525 3650);
DISPLAY INVISIBLE (-525 3650);
FORCEPROP 1 LAST BODY_TYPE PLUMBING
J 0
(-525 3700);
DISPLAY 0.872340 (-525 3700);
PAINT GREEN (-525 3700);
DISPLAY INVISIBLE (-525 3700);
FORCEPROP 1 LAST HDL_TAP TRUE
J 0
(-200 3525);
DISPLAY 0.872340 (-200 3525);
DISPLAY INVISIBLE (-200 3525);
FORCEPROP 1 LAST PATH I98
J 0
(-527 3650);
DISPLAY 0.872340 (-527 3650);
PAINT GREEN (-527 3650);
DISPLAY INVISIBLE (-527 3650);
FORCEADD TAP..1
(-525 3600);
FORCEPROP 3 LASTPIN (-575 3600) SIG_NAME M_B_CPU0_SA_DQ<15>
J 0
(-565 3610);
DISPLAY 0.659574 (-565 3610);
PAINT MONO (-565 3610);
DISPLAY INVISIBLE (-565 3610);
FORCEPROP 1 LASTPIN (-575 3600) BN 15
J 0
(-587 3608);
DISPLAY 0.680851 (-587 3608);
PAINT GREEN (-587 3608);
FORCEPROP 2 LAST CDS_LIB standard
J 0
(-525 3600);
PAINT MONO (-525 3600);
DISPLAY INVISIBLE (-525 3600);
FORCEPROP 1 LAST BODY_TYPE PLUMBING
J 0
(-525 3650);
DISPLAY 0.872340 (-525 3650);
PAINT GREEN (-525 3650);
DISPLAY INVISIBLE (-525 3650);
FORCEPROP 1 LAST HDL_TAP TRUE
J 0
(-200 3475);
DISPLAY 0.872340 (-200 3475);
DISPLAY INVISIBLE (-200 3475);
FORCEPROP 1 LAST PATH I99
J 0
(-527 3600);
DISPLAY 0.872340 (-527 3600);
PAINT GREEN (-527 3600);
DISPLAY INVISIBLE (-527 3600);
FORCEADD CAD_NOTE..1
(1325 -50);
FORCEPROP 0 LAST S1 PLACE THE BYPASS CAPS CLOSE TO DIMM
J 0
(1200 -175);
DISPLAY 1.021277 (1200 -175);
PAINT WHITE (1200 -175);
FORCEPROP 2 LAST CDS_LIB logical_power
J 0
(1325 -50);
PAINT MONO (1325 -50);
DISPLAY INVISIBLE (1325 -50);
FORCEPROP 1 LAST COMMENT_BODY TRUE
J 0
(1350 50);
DISPLAY 0.978723 (1350 50);
DISPLAY INVISIBLE (1350 50);
FORCEADD QUANTA_TITLE_BLOCK_C..1
(5775 -1325);
FORCEPROP 0 LAST CDS_CON_LAST_MODIFIED Fri Aug 25 14:01:04 2023
J 0
(3890 -1310);
PAINT MONO (3890 -1310);
DISPLAY INVISIBLE (3890 -1310);
FORCEPROP 1 LAST CUSTOM_TXT_CDS <CON_LAST_MODIFIED>
J 0
(3890 -1310);
DISPLAY 0.978723 (3890 -1310);
FORCEPROP 2 LAST CUSTOM_TXT_CDS <XR_PAGE_TITLE>
J 0
(-2115 3925);
DISPLAY 0.638298 (-2115 3925);
PAINT PINK (-2115 3925);
DISPLAY INVISIBLE (-2115 3925);
FORCEPROP 2 LAST CUSTOM_TXT_CDS <Q_NUMBER>
J 0
(4372 -1222);
DISPLAY 1.212766 (4372 -1222);
FORCEPROP 1 LAST CUSTOM_TXT_CDS <NAME_2>
J 0
(2600 -1275);
FORCEPROP 1 LAST CUSTOM_TXT_CDS <NAME_1>
J 0
(2600 -1150);
FORCEPROP 1 LAST CUSTOM_TXT_CDS <Q_PROJ>
J 0
(3393 -1223);
DISPLAY 1.212766 (3393 -1223);
FORCEPROP 1 LAST CUSTOM_TXT_CDS <Q_REV>
J 0
(5591 -1222);
DISPLAY 1.212766 (5591 -1222);
FORCEPROP 1 LAST CUSTOM_TXT_CDS <CON_PAGE_NUM> OF <CON_TOTAL_PAGES>
J 0
(5329 -1307);
DISPLAY 0.978723 (5329 -1307);
FORCEPROP 1 LAST Q_TITLE DDR5 - CPU0 CHB DIMM2(BLACK)
J 0
(-3591 -1299);
DISPLAY 2.446809 (-3591 -1299);
PAINT GREEN (-3591 -1299);
FORCEPROP 1 LAST Q_DEPT 
J 1
(2012 -1276);
DISPLAY 1.957447 (2012 -1276);
PAINT GREEN (2012 -1276);
FORCEPROP 1 LAST COMMENT_BODY TRUE
J 0
(5787 -1338);
DISPLAY 0.978723 (5787 -1338);
PAINT GREEN (5787 -1338);
DISPLAY INVISIBLE (5787 -1338);
FORCEPROP 2 LAST CDS_XR_PAGE_TITLE CR-85 : @S9S_MB_2U_LIB.S9S_MB_2U(SCH_1):PAGE85
J 0
(-2115 3925);
DISPLAY 0.638298 (-2115 3925);
PAINT PINK (-2115 3925);
DISPLAY INVISIBLE (-2115 3925);
FORCEPROP 2 LAST PAGE_BORDER TRUE
J 0
(-2115 3925);
DISPLAY 0.638298 (-2115 3925);
PAINT PINK (-2115 3925);
DISPLAY INVISIBLE (-2115 3925);
FORCEPROP 1 LAST CDS_LMAN_SYM_OUTLINE -9475,6775,100,-125
J 0
(5775 -1325);
DISPLAY 0.468085 (5775 -1325);
PAINT GREEN (5775 -1325);
DISPLAY INVISIBLE (5775 -1325);
FORCEPROP 2 LAST CDS_LIB pure_quanta
J 0
(5775 -1325);
PAINT MONO (5775 -1325);
DISPLAY INVISIBLE (5775 -1325);
WIRE 17 -1 (-475 4375)(-475 4425);
WIRE 17 -1 (-475 4325)(-475 4375);
WIRE 17 -1 (-475 4425)(250 4425);
FORCEPROP 2 LAST SIG_NAME M_B_CPU0_SA_DQ<31:0>
J 0
(-410 4435);
DISPLAY 0.680851 (-410 4435);
PAINT WHITE (-410 4435);
WIRE 17 -1 (-2225 2975)(-2225 3025);
WIRE 17 -1 (-2225 2925)(-2225 2975);
WIRE 17 -1 (-3050 3025)(-2225 3025);
FORCEPROP 2 LAST SIG_NAME M_B_CPU0_SA_CB<7:0>
J 0
(-2960 3035);
DISPLAY 0.680851 (-2960 3035);
PAINT WHITE (-2960 3035);
WIRE 17 -1 (-2225 2875)(-2225 2925);
WIRE 17 -1 (-2225 2825)(-2225 2875);
WIRE 17 -1 (-2225 2775)(-2225 2825);
WIRE 17 -1 (-2225 2725)(-2225 2775);
WIRE 17 -1 (-2225 2675)(-2225 2725);
WIRE 17 -1 (-2225 4125)(-2225 4175);
WIRE 17 -1 (-2225 4175)(-2225 4225);
WIRE 17 -1 (-2225 4225)(-2225 4275);
WIRE 17 -1 (-2225 4275)(-2225 4325);
WIRE 17 -1 (-2225 4325)(-2225 4375);
WIRE 17 -1 (-2225 4375)(-2225 4425);
WIRE 17 -1 (-3050 4425)(-2225 4425);
FORCEPROP 2 LAST SIG_NAME M_B_CPU0_SA_CA<6:0>
J 0
(-2960 4435);
DISPLAY 0.680851 (-2960 4435);
PAINT WHITE (-2960 4435);
WIRE 17 -1 (-2225 3725)(-2225 3775);
WIRE 17 -1 (-2225 3775)(-2225 3825);
WIRE 17 -1 (-2225 3825)(-2225 3875);
WIRE 17 -1 (-2225 3875)(-2225 3925);
WIRE 17 -1 (-2225 3925)(-2225 3975);
WIRE 17 -1 (-2225 3975)(-2225 4025);
WIRE 17 -1 (-3050 4025)(-2225 4025);
FORCEPROP 2 LAST SIG_NAME M_B_CPU0_SB_CA<6:0>
J 0
(-2960 4035);
DISPLAY 0.680851 (-2960 4035);
PAINT WHITE (-2960 4035);
WIRE 17 -1 (-2225 2525)(-2225 2575);
WIRE 17 -1 (-2225 2475)(-2225 2525);
WIRE 17 -1 (-3050 2575)(-2225 2575);
FORCEPROP 2 LAST SIG_NAME M_B_CPU0_SB_CB<7:0>
J 0
(-2960 2585);
DISPLAY 0.680851 (-2960 2585);
PAINT WHITE (-2960 2585);
WIRE 17 -1 (-2225 2425)(-2225 2475);
WIRE 17 -1 (-2225 2375)(-2225 2425);
WIRE 17 -1 (-2225 2325)(-2225 2375);
WIRE 17 -1 (-2225 2275)(-2225 2325);
WIRE 17 -1 (-2225 2225)(-2225 2275);
WIRE 17 -1 (-475 4275)(-475 4325);
WIRE 17 -1 (-475 4225)(-475 4275);
WIRE 17 -1 (-475 4175)(-475 4225);
WIRE 17 -1 (-475 4125)(-475 4175);
WIRE 17 -1 (-475 4075)(-475 4125);
WIRE 17 -1 (-475 4025)(-475 4075);
WIRE 17 -1 (-475 3975)(-475 4025);
WIRE 17 -1 (-475 3925)(-475 3975);
WIRE 17 -1 (-475 3875)(-475 3925);
WIRE 17 -1 (-475 3825)(-475 3875);
WIRE 17 -1 (-475 3775)(-475 3825);
WIRE 17 -1 (-475 3725)(-475 3775);
WIRE 17 -1 (-475 3675)(-475 3725);
WIRE 17 -1 (-475 3625)(-475 3675);
WIRE 17 -1 (-475 3575)(-475 3625);
WIRE 17 -1 (-475 3525)(-475 3575);
WIRE 17 -1 (-475 3475)(-475 3525);
WIRE 17 -1 (-475 3425)(-475 3475);
WIRE 17 -1 (-475 3375)(-475 3425);
WIRE 17 -1 (-475 3325)(-475 3375);
WIRE 17 -1 (-475 3275)(-475 3325);
WIRE 17 -1 (-475 3225)(-475 3275);
WIRE 17 -1 (-475 3175)(-475 3225);
WIRE 17 -1 (-475 3125)(-475 3175);
WIRE 17 -1 (-475 3075)(-475 3125);
WIRE 17 -1 (-475 3025)(-475 3075);
WIRE 17 -1 (-475 2975)(-475 3025);
WIRE 17 -1 (-475 2925)(-475 2975);
WIRE 17 -1 (-475 2875)(-475 2925);
WIRE 17 -1 (-475 2725)(-475 2775);
WIRE 17 -1 (-475 2675)(-475 2725);
WIRE 17 -1 (-475 2775)(250 2775);
FORCEPROP 2 LAST SIG_NAME M_B_CPU0_SB_DQ<31:0>
J 0
(-410 2785);
DISPLAY 0.680851 (-410 2785);
PAINT WHITE (-410 2785);
WIRE 17 -1 (-475 2625)(-475 2675);
WIRE 17 -1 (-475 2575)(-475 2625);
WIRE 17 -1 (-475 2525)(-475 2575);
WIRE 17 -1 (-475 2475)(-475 2525);
WIRE 17 -1 (-475 2425)(-475 2475);
WIRE 17 -1 (-475 2375)(-475 2425);
WIRE 17 -1 (-475 2325)(-475 2375);
WIRE 17 -1 (-475 2275)(-475 2325);
WIRE 17 -1 (-475 2225)(-475 2275);
WIRE 17 -1 (-475 2175)(-475 2225);
WIRE 17 -1 (-475 2125)(-475 2175);
WIRE 17 -1 (-475 2075)(-475 2125);
WIRE 17 -1 (-475 2025)(-475 2075);
WIRE 17 -1 (-475 1975)(-475 2025);
WIRE 17 -1 (-475 1925)(-475 1975);
WIRE 17 -1 (-475 1875)(-475 1925);
WIRE 17 -1 (-475 1825)(-475 1875);
WIRE 17 -1 (-475 1775)(-475 1825);
WIRE 17 -1 (-475 1725)(-475 1775);
WIRE 17 -1 (-475 1675)(-475 1725);
WIRE 17 -1 (-475 1625)(-475 1675);
WIRE 17 -1 (-475 1575)(-475 1625);
WIRE 17 -1 (-475 1525)(-475 1575);
WIRE 17 -1 (-475 1475)(-475 1525);
WIRE 17 -1 (-475 1425)(-475 1475);
WIRE 17 -1 (-475 1375)(-475 1425);
WIRE 17 -1 (-475 1325)(-475 1375);
WIRE 17 -1 (-475 1275)(-475 1325);
WIRE 17 -1 (-475 1225)(-475 1275);
WIRE 17 -1 (2275 4325)(2275 4425);
WIRE 17 -1 (2275 4225)(2275 4325);
WIRE 17 -1 (2275 4425)(3300 4425);
FORCEPROP 2 LAST SIG_NAME M_B_CPU0_SA_DQS_DP<9:0>
J 0
(2515 4435);
DISPLAY 0.680851 (2515 4435);
PAINT WHITE (2515 4435);
WIRE 17 -1 (2275 4125)(2275 4225);
WIRE 17 -1 (2275 4025)(2275 4125);
WIRE 17 -1 (2275 3925)(2275 4025);
WIRE 17 -1 (2275 3925)(2275 3825);
WIRE 17 -1 (2275 3725)(2275 3825);
WIRE 17 -1 (2275 3625)(2275 3725);
WIRE 17 -1 (2275 3525)(2275 3625);
WIRE 17 -1 (2275 3275)(2275 3375);
WIRE 17 -1 (2275 3175)(2275 3275);
WIRE 17 -1 (2275 3375)(3300 3375);
FORCEPROP 2 LAST SIG_NAME M_B_CPU0_SB_DQS_DP<9:0>
J 0
(2515 3385);
DISPLAY 0.680851 (2515 3385);
PAINT WHITE (2515 3385);
WIRE 17 -1 (2275 3075)(2275 3175);
WIRE 17 -1 (2275 2975)(2275 3075);
WIRE 17 -1 (2275 2875)(2275 2975);
WIRE 17 -1 (2275 2875)(2275 2775);
WIRE 17 -1 (2275 2675)(2275 2775);
WIRE 17 -1 (2275 2575)(2275 2675);
WIRE 17 -1 (2275 2475)(2275 2575);
WIRE 17 -1 (2450 4175)(2450 4275);
WIRE 17 -1 (2450 4075)(2450 4175);
WIRE 17 -1 (2450 4275)(2450 4375);
WIRE 17 -1 (2450 4375)(3300 4375);
FORCEPROP 2 LAST SIG_NAME M_B_CPU0_SA_DQS_DN<9:0>
J 0
(2515 4385);
DISPLAY 0.680851 (2515 4385);
PAINT WHITE (2515 4385);
WIRE 17 -1 (2450 3975)(2450 4075);
WIRE 17 -1 (2450 3875)(2450 3975);
WIRE 17 -1 (2450 3875)(2450 3775);
WIRE 17 -1 (2450 3675)(2450 3775);
WIRE 17 -1 (2450 3575)(2450 3675);
WIRE 17 -1 (2450 3475)(2450 3575);
WIRE 17 -1 (2450 3225)(2450 3325);
WIRE 17 -1 (2450 3125)(2450 3225);
WIRE 17 -1 (2450 3325)(3300 3325);
FORCEPROP 2 LAST SIG_NAME M_B_CPU0_SB_DQS_DN<9:0>
J 0
(2515 3335);
DISPLAY 0.680851 (2515 3335);
PAINT WHITE (2515 3335);
WIRE 17 -1 (2450 3025)(2450 3125);
WIRE 17 -1 (2450 2925)(2450 3025);
WIRE 17 -1 (2450 2825)(2450 2925);
WIRE 17 -1 (2450 2825)(2450 2725);
WIRE 17 -1 (2450 2625)(2450 2725);
WIRE 17 -1 (2450 2525)(2450 2625);
WIRE 17 -1 (2450 2425)(2450 2525);
WIRE 16 -1 (1200 625)(1200 800);
WIRE 16 -1 (-3000 2225)(-3000 1950);
WIRE 16 -1 (3900 4900)(3900 4400);
WIRE 16 -1 (2200 800)(2200 750);
WIRE 16 -1 (-1950 75)(-1950 150);
WIRE 16 -1 (5600 1050)(5600 750);
WIRE 16 -1 (5600 1100)(5600 1050);
WIRE 16 -1 (5350 1050)(5600 1050);
WIRE 16 -1 (3900 750)(3900 1150);
WIRE 16 -1 (2825 200)(2825 275);
WIRE 16 -1 (1200 425)(1200 200);
WIRE 16 3135 (850 1025)(850 -275);
WIRE 16 3135 (3450 1025)(850 1025);
WIRE 16 3135 (850 -275)(3450 -275);
WIRE 16 3135 (3450 -275)(3450 1025);
WIRE 16 -1 (2200 275)(2200 425);
WIRE 16 -1 (2825 275)(2200 275);
WIRE 16 -1 (2825 275)(2825 425);
WIRE 16 -1 (-3000 1950)(-1950 1950);
WIRE 16 -1 (-1950 1850)(-2950 1850);
FORCEPROP 2 LAST SIG_NAME I3C_SPD_DDRABCD_CPU0_LVC1_SDA
J 0
(-2960 1860);
DISPLAY 0.680851 (-2960 1860);
PAINT WHITE (-2960 1860);
WIRE 16 -1 (-1950 1900)(-2950 1900);
FORCEPROP 2 LAST SIG_NAME PD_CHB_CPU0_DIMM2_SAA
J 0
(-2960 1910);
DISPLAY 0.680851 (-2960 1910);
PAINT WHITE (-2960 1910);
WIRE 16 -1 (-1950 2050)(-3050 2050);
FORCEPROP 2 LAST SIG_NAME M_B_CPU0_ALERT_N
J 0
(-2962 2059);
DISPLAY 0.680851 (-2962 2059);
PAINT WHITE (-2962 2059);
WIRE 16 -1 (-2325 2150)(-3050 2150);
FORCEPROP 2 LAST SIG_NAME RST_M_AB_CPU0_FPGA_N
J 0
(-2962 2159);
DISPLAY 0.680851 (-2962 2159);
PAINT WHITE (-2962 2159);
WIRE 16 -1 (-2325 2150)(-2325 2100);
WIRE 16 -1 (-2325 2100)(-1950 2100);
WIRE 16 -1 (-2125 2350)(-1950 2350);
WIRE 16 -1 (-750 1950)(-575 1950);
WIRE 16 -1 (-3525 1700)(-3375 1700);
WIRE 16 -1 (-3525 1800)(-3525 1700);
WIRE 16 -1 (-3525 1800)(-1950 1800);
FORCEPROP 2 LAST SIG_NAME I3C_SPD_DDRABCD_CPU0_LVC1_SCL_R4
J 0
(-3010 1810);
DISPLAY 0.680851 (-3010 1810);
PAINT WHITE (-3010 1810);
WIRE 16 -1 (-1925 1625)(-1975 1625);
WIRE 16 -1 (-1925 1700)(-1925 1625);
WIRE 16 -1 (-3175 1700)(-1925 1700);
FORCEPROP 2 LAST SIG_NAME I3C_SPD_DDRABCD_CPU0_LVC1_SCL
J 0
(-3060 1710);
DISPLAY 0.680851 (-3060 1710);
PAINT WHITE (-3060 1710);
WIRE 16 -1 (-1950 1550)(-3050 1550);
FORCEPROP 2 LAST SIG_NAME PWRGD_CHB_CPU0_DIMM2
J 0
(-2962 1559);
DISPLAY 0.680851 (-2962 1559);
PAINT WHITE (-2962 1559);
WIRE 16 -1 (-1950 1450)(-3050 1450);
FORCEPROP 2 LAST SIG_NAME TP_CHB_CPU0_DIMM2_FRU_6
J 0
(-2962 1459);
DISPLAY 0.680851 (-2962 1459);
PAINT WHITE (-2962 1459);
WIRE 16 -1 (-1950 1200)(-3050 1200);
FORCEPROP 2 LAST SIG_NAME TP_CHB_CPU0_DIMM2_FRU_1
J 0
(-2962 1209);
DISPLAY 0.680851 (-2962 1209);
PAINT WHITE (-2962 1209);
WIRE 16 -1 (-1950 1250)(-3050 1250);
FORCEPROP 2 LAST SIG_NAME TP_CHB_CPU0_DIMM2_FRU_2
J 0
(-2962 1259);
DISPLAY 0.680851 (-2962 1259);
PAINT WHITE (-2962 1259);
WIRE 16 -1 (-1950 1300)(-3050 1300);
FORCEPROP 2 LAST SIG_NAME TP_CHB_CPU0_DIMM2_FRU_3
J 0
(-2962 1309);
DISPLAY 0.680851 (-2962 1309);
PAINT WHITE (-2962 1309);
WIRE 16 -1 (-1950 1350)(-3050 1350);
FORCEPROP 2 LAST SIG_NAME TP_CHB_CPU0_DIMM2_FRU_4
J 0
(-2962 1359);
DISPLAY 0.680851 (-2962 1359);
PAINT WHITE (-2962 1359);
WIRE 16 -1 (-1950 1400)(-3050 1400);
FORCEPROP 2 LAST SIG_NAME TP_CHB_CPU0_DIMM2_FRU_5
J 0
(-2962 1409);
DISPLAY 0.680851 (-2962 1409);
PAINT WHITE (-2962 1409);
WIRE 16 -1 (-1950 3150)(-3050 3150);
FORCEPROP 2 LAST SIG_NAME M_B_CPU0_CLK_DP<1>
J 0
(-2962 3159);
DISPLAY 0.680851 (-2962 3159);
PAINT WHITE (-2962 3159);
WIRE 16 -1 (2075 2400)(2350 2400);
WIRE 16 -1 (2075 2500)(2350 2500);
WIRE 16 -1 (2075 2600)(2350 2600);
WIRE 16 -1 (2075 2800)(2350 2800);
WIRE 16 -1 (2075 2700)(2350 2700);
WIRE 16 -1 (2075 2900)(2350 2900);
WIRE 16 -1 (2075 3000)(2350 3000);
WIRE 16 -1 (2075 3100)(2350 3100);
WIRE 16 -1 (2075 3200)(2350 3200);
WIRE 16 -1 (2075 3300)(2350 3300);
WIRE 16 -1 (2075 3450)(2350 3450);
WIRE 16 -1 (2075 3550)(2350 3550);
WIRE 16 -1 (2075 3650)(2350 3650);
WIRE 16 -1 (2075 3750)(2350 3750);
WIRE 16 -1 (2075 3850)(2350 3850);
WIRE 16 -1 (2075 3950)(2350 3950);
WIRE 16 -1 (2075 4050)(2350 4050);
WIRE 16 -1 (2075 4150)(2350 4150);
WIRE 16 -1 (2350 4350)(2075 4350);
WIRE 16 -1 (2075 4250)(2350 4250);
WIRE 16 -1 (2075 2550)(2175 2550);
WIRE 16 -1 (2075 2450)(2175 2450);
WIRE 16 -1 (2075 2650)(2175 2650);
WIRE 16 -1 (2075 2750)(2175 2750);
WIRE 16 -1 (2075 3050)(2175 3050);
WIRE 16 -1 (2075 2850)(2175 2850);
WIRE 16 -1 (2075 2950)(2175 2950);
WIRE 16 -1 (2075 3150)(2175 3150);
WIRE 16 -1 (2075 3250)(2175 3250);
WIRE 16 -1 (2075 3500)(2175 3500);
WIRE 16 -1 (2075 3350)(2175 3350);
WIRE 16 -1 (2075 3600)(2175 3600);
WIRE 16 -1 (2075 3700)(2175 3700);
WIRE 16 -1 (2075 3800)(2175 3800);
WIRE 16 -1 (2075 3900)(2175 3900);
WIRE 16 -1 (2075 4000)(2175 4000);
WIRE 16 -1 (2075 4100)(2175 4100);
WIRE 16 -1 (2075 4200)(2175 4200);
WIRE 16 -1 (2075 4300)(2175 4300);
WIRE 16 -1 (2075 4400)(2175 4400);
WIRE 16 -1 (-750 3450)(-575 3450);
WIRE 16 -1 (-2125 2300)(-1950 2300);
WIRE 16 -1 (-750 1800)(-575 1800);
WIRE 16 -1 (-2125 2200)(-1950 2200);
WIRE 16 -1 (4150 4300)(3900 4300);
WIRE 16 -1 (3900 4350)(3900 4300);
WIRE 16 -1 (3900 4350)(4150 4350);
WIRE 16 -1 (3900 4400)(3900 4350);
WIRE 16 -1 (4150 4400)(3900 4400);
WIRE 16 -1 (-750 3800)(-575 3800);
WIRE 16 -1 (-750 3750)(-575 3750);
WIRE 16 -1 (-2125 2550)(-1950 2550);
WIRE 16 -1 (-750 2400)(-575 2400);
WIRE 16 -1 (-750 2350)(-575 2350);
WIRE 16 -1 (4150 4250)(3900 4250);
WIRE 16 -1 (3900 4200)(3900 4250);
WIRE 16 -1 (3900 4200)(4150 4200);
WIRE 16 -1 (3900 4150)(3900 4200);
WIRE 16 -1 (4150 4150)(3900 4150);
WIRE 16 -1 (3900 4100)(3900 4150);
WIRE 16 -1 (3900 4100)(4150 4100);
WIRE 16 -1 (3900 4050)(3900 4100);
WIRE 16 -1 (3900 4050)(4150 4050);
WIRE 16 -1 (3900 4000)(3900 4050);
WIRE 16 -1 (3900 4000)(4150 4000);
WIRE 16 -1 (3900 3950)(3900 4000);
WIRE 16 -1 (3900 3950)(4150 3950);
WIRE 16 -1 (3900 3900)(3900 3950);
WIRE 16 -1 (3900 3900)(4150 3900);
WIRE 16 -1 (3900 3850)(3900 3900);
WIRE 16 -1 (3900 3850)(4150 3850);
WIRE 16 -1 (3900 3800)(3900 3850);
WIRE 16 -1 (3900 3800)(4150 3800);
WIRE 16 -1 (3900 3750)(3900 3800);
WIRE 16 -1 (3900 3750)(4150 3750);
WIRE 16 -1 (3900 3700)(3900 3750);
WIRE 16 -1 (3900 3700)(4150 3700);
WIRE 16 -1 (3900 3650)(3900 3700);
WIRE 16 -1 (4150 3650)(3900 3650);
WIRE 16 -1 (3900 3600)(3900 3650);
WIRE 16 -1 (3900 3600)(4150 3600);
WIRE 16 -1 (3900 3550)(3900 3600);
WIRE 16 -1 (3900 3550)(4150 3550);
WIRE 16 -1 (3900 3500)(3900 3550);
WIRE 16 -1 (3900 3500)(4150 3500);
WIRE 16 -1 (3900 3450)(3900 3500);
WIRE 16 -1 (3900 3450)(4150 3450);
WIRE 16 -1 (3900 3400)(3900 3450);
WIRE 16 -1 (3900 3400)(4150 3400);
WIRE 16 -1 (3900 3350)(3900 3400);
WIRE 16 -1 (3900 3350)(4150 3350);
WIRE 16 -1 (3900 3300)(3900 3350);
WIRE 16 -1 (3900 3300)(4150 3300);
WIRE 16 -1 (3900 3250)(3900 3300);
WIRE 16 -1 (3900 3250)(4150 3250);
WIRE 16 -1 (3900 3200)(3900 3250);
WIRE 16 -1 (3900 3200)(4150 3200);
WIRE 16 -1 (3900 3150)(3900 3200);
WIRE 16 -1 (4150 3150)(3900 3150);
WIRE 16 -1 (3900 3100)(3900 3150);
WIRE 16 -1 (3900 3100)(4150 3100);
WIRE 16 -1 (3900 3050)(3900 3100);
WIRE 16 -1 (3900 3050)(4150 3050);
WIRE 16 -1 (3900 3000)(3900 3050);
WIRE 16 -1 (3900 3000)(4150 3000);
WIRE 16 -1 (3900 2950)(3900 3000);
WIRE 16 -1 (3900 2950)(4150 2950);
WIRE 16 -1 (3900 2900)(3900 2950);
WIRE 16 -1 (3900 2900)(4150 2900);
WIRE 16 -1 (3900 2850)(3900 2900);
WIRE 16 -1 (3900 2850)(4150 2850);
WIRE 16 -1 (3900 2800)(3900 2850);
WIRE 16 -1 (3900 2800)(4150 2800);
WIRE 16 -1 (3900 2750)(3900 2800);
WIRE 16 -1 (3900 2750)(4150 2750);
WIRE 16 -1 (3900 2700)(3900 2750);
WIRE 16 -1 (3900 2700)(4150 2700);
WIRE 16 -1 (3900 2650)(3900 2700);
WIRE 16 -1 (4150 2650)(3900 2650);
WIRE 16 -1 (3900 2600)(3900 2650);
WIRE 16 -1 (3900 2600)(4150 2600);
WIRE 16 -1 (3900 2550)(3900 2600);
WIRE 16 -1 (3900 2550)(4150 2550);
WIRE 16 -1 (3900 2500)(3900 2550);
WIRE 16 -1 (3900 2500)(4150 2500);
WIRE 16 -1 (3900 2450)(3900 2500);
WIRE 16 -1 (3900 2450)(4150 2450);
WIRE 16 -1 (3900 2400)(3900 2450);
WIRE 16 -1 (3900 2400)(4150 2400);
WIRE 16 -1 (3900 2350)(3900 2400);
WIRE 16 -1 (3900 2350)(4150 2350);
WIRE 16 -1 (3900 2300)(3900 2350);
WIRE 16 -1 (3900 2300)(4150 2300);
WIRE 16 -1 (3900 2250)(3900 2300);
WIRE 16 -1 (3900 2250)(4150 2250);
WIRE 16 -1 (3900 2200)(3900 2250);
WIRE 16 -1 (3900 2200)(4150 2200);
WIRE 16 -1 (3900 2150)(3900 2200);
WIRE 16 -1 (4150 2150)(3900 2150);
WIRE 16 -1 (3900 2100)(3900 2150);
WIRE 16 -1 (3900 2100)(4150 2100);
WIRE 16 -1 (3900 2050)(3900 2100);
WIRE 16 -1 (3900 2050)(4150 2050);
WIRE 16 -1 (3900 2000)(3900 2050);
WIRE 16 -1 (3900 2000)(4150 2000);
WIRE 16 -1 (3900 1950)(3900 2000);
WIRE 16 -1 (3900 1950)(4150 1950);
WIRE 16 -1 (3900 1900)(3900 1950);
WIRE 16 -1 (3900 1900)(4150 1900);
WIRE 16 -1 (3900 1850)(3900 1900);
WIRE 16 -1 (3900 1850)(4150 1850);
WIRE 16 -1 (3900 1800)(3900 1850);
WIRE 16 -1 (3900 1800)(4150 1800);
WIRE 16 -1 (3900 1750)(3900 1800);
WIRE 16 -1 (3900 1750)(4150 1750);
WIRE 16 -1 (3900 1700)(3900 1750);
WIRE 16 -1 (3900 1700)(4150 1700);
WIRE 16 -1 (3900 1650)(3900 1700);
WIRE 16 -1 (4150 1650)(3900 1650);
WIRE 16 -1 (3900 1600)(3900 1650);
WIRE 16 -1 (3900 1600)(4150 1600);
WIRE 16 -1 (3900 1550)(3900 1600);
WIRE 16 -1 (3900 1550)(4150 1550);
WIRE 16 -1 (3900 1500)(3900 1550);
WIRE 16 -1 (3900 1500)(4150 1500);
WIRE 16 -1 (3900 1450)(3900 1500);
WIRE 16 -1 (3900 1450)(4150 1450);
WIRE 16 -1 (3900 1400)(3900 1450);
WIRE 16 -1 (3900 1400)(4150 1400);
WIRE 16 -1 (3900 1350)(3900 1400);
WIRE 16 -1 (3900 1350)(4150 1350);
WIRE 16 -1 (3900 1300)(3900 1350);
WIRE 16 -1 (3900 1300)(4150 1300);
WIRE 16 -1 (3900 1250)(3900 1300);
WIRE 16 -1 (3900 1250)(4150 1250);
WIRE 16 -1 (3900 1200)(3900 1250);
WIRE 16 -1 (3900 1200)(4150 1200);
WIRE 16 -1 (3900 1150)(3900 1200);
WIRE 16 -1 (3900 1150)(4150 1150);
WIRE 16 -1 (-1950 1150)(-3050 1150);
FORCEPROP 2 LAST SIG_NAME TP_CHB_CPU0_DIMM2_FRU_0
J 0
(-2962 1159);
DISPLAY 0.680851 (-2962 1159);
PAINT WHITE (-2962 1159);
WIRE 16 -1 (-1950 3550)(-3050 3550);
FORCEPROP 2 LAST SIG_NAME M_B_CPU0_SB_PAR
J 0
(-2962 3559);
DISPLAY 0.680851 (-2962 3559);
PAINT WHITE (-2962 3559);
WIRE 16 -1 (-1950 3600)(-3050 3600);
FORCEPROP 2 LAST SIG_NAME M_B_CPU0_SA_PAR
J 0
(-2962 3609);
DISPLAY 0.680851 (-2962 3609);
PAINT WHITE (-2962 3609);
WIRE 16 -1 (-1950 950)(-3050 950);
FORCEPROP 2 LAST SIG_NAME M_B_CPU0_SB_RSP<1>
J 0
(-2962 959);
DISPLAY 0.680851 (-2962 959);
PAINT WHITE (-2962 959);
WIRE 16 -1 (-1950 1000)(-3050 1000);
FORCEPROP 2 LAST SIG_NAME M_B_CPU0_SA_RSP<1>
J 0
(-2962 1009);
DISPLAY 0.680851 (-2962 1009);
PAINT WHITE (-2962 1009);
WIRE 16 -1 (-750 1200)(-575 1200);
WIRE 16 -1 (-750 1250)(-575 1250);
WIRE 16 -1 (-750 1300)(-575 1300);
WIRE 16 -1 (-750 1350)(-575 1350);
WIRE 16 -1 (-750 1400)(-575 1400);
WIRE 16 -1 (-750 1450)(-575 1450);
WIRE 16 -1 (-750 1500)(-575 1500);
WIRE 16 -1 (-750 1550)(-575 1550);
WIRE 16 -1 (-750 1600)(-575 1600);
WIRE 16 -1 (-750 1650)(-575 1650);
WIRE 16 -1 (-750 1700)(-575 1700);
WIRE 16 -1 (-750 1750)(-575 1750);
WIRE 16 -1 (-750 1850)(-575 1850);
WIRE 16 -1 (-750 1900)(-575 1900);
WIRE 16 -1 (-750 2000)(-575 2000);
WIRE 16 -1 (-750 2050)(-575 2050);
WIRE 16 -1 (-750 2100)(-575 2100);
WIRE 16 -1 (-750 2150)(-575 2150);
WIRE 16 -1 (-750 2200)(-575 2200);
WIRE 16 -1 (-750 2250)(-575 2250);
WIRE 16 -1 (-750 2300)(-575 2300);
WIRE 16 -1 (-750 2450)(-575 2450);
WIRE 16 -1 (-750 2500)(-575 2500);
WIRE 16 -1 (-750 2550)(-575 2550);
WIRE 16 -1 (-750 2600)(-575 2600);
WIRE 16 -1 (-750 2650)(-575 2650);
WIRE 16 -1 (-750 2700)(-575 2700);
WIRE 16 -1 (-750 2750)(-575 2750);
WIRE 16 -1 (-750 2850)(-575 2850);
WIRE 16 -1 (-750 2900)(-575 2900);
WIRE 16 -1 (-750 2950)(-575 2950);
WIRE 16 -1 (-750 3000)(-575 3000);
WIRE 16 -1 (-750 3050)(-575 3050);
WIRE 16 -1 (-750 3100)(-575 3100);
WIRE 16 -1 (-750 3150)(-575 3150);
WIRE 16 -1 (-750 3200)(-575 3200);
WIRE 16 -1 (-750 3250)(-575 3250);
WIRE 16 -1 (-750 3300)(-575 3300);
WIRE 16 -1 (-750 3350)(-575 3350);
WIRE 16 -1 (-750 3400)(-575 3400);
WIRE 16 -1 (-750 3500)(-575 3500);
WIRE 16 -1 (-750 3550)(-575 3550);
WIRE 16 -1 (-750 3600)(-575 3600);
WIRE 16 -1 (-750 3650)(-575 3650);
WIRE 16 -1 (-750 3700)(-575 3700);
WIRE 16 -1 (-750 3850)(-575 3850);
WIRE 16 -1 (-750 3900)(-575 3900);
WIRE 16 -1 (-750 3950)(-575 3950);
WIRE 16 -1 (-750 4000)(-575 4000);
WIRE 16 -1 (-750 4050)(-575 4050);
WIRE 16 -1 (-750 4100)(-575 4100);
WIRE 16 -1 (-750 4150)(-575 4150);
WIRE 16 -1 (-750 4200)(-575 4200);
WIRE 16 -1 (-750 4250)(-575 4250);
WIRE 16 -1 (-750 4300)(-575 4300);
WIRE 16 -1 (-750 4350)(-575 4350);
WIRE 16 -1 (-1950 3300)(-3050 3300);
FORCEPROP 2 LAST SIG_NAME M_B_CPU0_SB_CS_N<3>
J 0
(-2962 3309);
DISPLAY 0.680851 (-2962 3309);
PAINT WHITE (-2962 3309);
WIRE 16 -1 (-1950 3450)(-3050 3450);
FORCEPROP 2 LAST SIG_NAME M_B_CPU0_SA_CS_N<3>
J 0
(-2962 3459);
DISPLAY 0.680851 (-2962 3459);
PAINT WHITE (-2962 3459);
WIRE 16 -1 (-1950 3250)(-3050 3250);
FORCEPROP 2 LAST SIG_NAME M_B_CPU0_SB_CS_N<2>
J 0
(-2962 3259);
DISPLAY 0.680851 (-2962 3259);
PAINT WHITE (-2962 3259);
WIRE 16 -1 (-1950 3400)(-3050 3400);
FORCEPROP 2 LAST SIG_NAME M_B_CPU0_SA_CS_N<2>
J 0
(-2962 3409);
DISPLAY 0.680851 (-2962 3409);
PAINT WHITE (-2962 3409);
WIRE 16 -1 (-1950 3100)(-3050 3100);
FORCEPROP 2 LAST SIG_NAME M_B_CPU0_CLK_DN<1>
J 0
(-2962 3109);
DISPLAY 0.680851 (-2962 3109);
PAINT WHITE (-2962 3109);
WIRE 16 -1 (-2125 2250)(-1950 2250);
WIRE 16 -1 (-2125 2400)(-1950 2400);
WIRE 16 -1 (-2125 2450)(-1950 2450);
WIRE 16 -1 (-2125 2500)(-1950 2500);
WIRE 16 -1 (-2125 2650)(-1950 2650);
WIRE 16 -1 (-2125 2750)(-1950 2750);
WIRE 16 -1 (-2125 2800)(-1950 2800);
WIRE 16 -1 (-2125 2900)(-1950 2900);
WIRE 16 -1 (-2125 2950)(-1950 2950);
WIRE 16 -1 (-2125 4000)(-1950 4000);
WIRE 16 -1 (-2125 4400)(-1950 4400);
WIRE 16 -1 (-2125 3950)(-1950 3950);
WIRE 16 -1 (-2125 4350)(-1950 4350);
WIRE 16 -1 (-2125 3900)(-1950 3900);
WIRE 16 -1 (-2125 4300)(-1950 4300);
WIRE 16 -1 (-2125 3850)(-1950 3850);
WIRE 16 -1 (-2125 4250)(-1950 4250);
WIRE 16 -1 (-2125 3800)(-1950 3800);
WIRE 16 -1 (-2125 4200)(-1950 4200);
WIRE 16 -1 (-2125 3750)(-1950 3750);
WIRE 16 -1 (-2125 4150)(-1950 4150);
WIRE 16 -1 (-2125 3700)(-1950 3700);
WIRE 16 -1 (-2125 4100)(-1950 4100);
WIRE 16 -1 (-2125 2700)(-1950 2700);
WIRE 16 -1 (-2125 2850)(-1950 2850);
WIRE 16 -1 (-2125 3000)(-1950 3000);
WIRE 16 -1 (-750 4400)(-575 4400);
WIRE 16 -1 (5350 1100)(5600 1100);
WIRE 16 -1 (5350 1150)(5600 1150);
WIRE 16 -1 (5600 1150)(5600 1100);
WIRE 16 -1 (5350 1250)(5600 1250);
WIRE 16 -1 (5600 1250)(5600 1150);
WIRE 16 -1 (5350 1300)(5600 1300);
WIRE 16 -1 (5600 1300)(5600 1250);
WIRE 16 -1 (5350 1350)(5600 1350);
WIRE 16 -1 (5600 1300)(5600 1350);
WIRE 16 -1 (5350 1400)(5600 1400);
WIRE 16 -1 (5600 1400)(5600 1350);
WIRE 16 -1 (5350 1450)(5600 1450);
WIRE 16 -1 (5600 1450)(5600 1400);
WIRE 16 -1 (5350 1500)(5600 1500);
WIRE 16 -1 (5600 1500)(5600 1450);
WIRE 16 -1 (5600 1550)(5600 1500);
WIRE 16 -1 (5350 1550)(5600 1550);
WIRE 16 -1 (5350 1600)(5600 1600);
WIRE 16 -1 (5600 1600)(5600 1550);
WIRE 16 -1 (5350 1650)(5600 1650);
WIRE 16 -1 (5600 1650)(5600 1600);
WIRE 16 -1 (5600 1700)(5350 1700);
WIRE 16 -1 (5600 1700)(5600 1650);
WIRE 16 -1 (5600 1750)(5350 1750);
WIRE 16 -1 (5600 1750)(5600 1700);
WIRE 16 -1 (5600 1800)(5350 1800);
WIRE 16 -1 (5600 1800)(5600 1750);
WIRE 16 -1 (5350 1850)(5600 1850);
WIRE 16 -1 (5600 1800)(5600 1850);
WIRE 16 -1 (5600 1900)(5350 1900);
WIRE 16 -1 (5600 1850)(5600 1900);
WIRE 16 -1 (5600 1950)(5350 1950);
WIRE 16 -1 (5600 1950)(5600 1900);
WIRE 16 -1 (5600 2000)(5350 2000);
WIRE 16 -1 (5600 2000)(5600 1950);
WIRE 16 -1 (5600 2050)(5600 2000);
WIRE 16 -1 (5600 2050)(5350 2050);
WIRE 16 -1 (5350 2100)(5600 2100);
WIRE 16 -1 (5600 2100)(5600 2050);
WIRE 16 -1 (5350 2150)(5600 2150);
WIRE 16 -1 (5600 2150)(5600 2100);
WIRE 16 -1 (5350 2200)(5600 2200);
WIRE 16 -1 (5600 2150)(5600 2200);
WIRE 16 -1 (5350 2250)(5600 2250);
WIRE 16 -1 (5600 2250)(5600 2200);
WIRE 16 -1 (5350 2300)(5600 2300);
WIRE 16 -1 (5600 2300)(5600 2250);
WIRE 16 -1 (5350 2350)(5600 2350);
WIRE 16 -1 (5600 2350)(5600 2300);
WIRE 16 -1 (5350 2400)(5600 2400);
WIRE 16 -1 (5600 2400)(5600 2350);
WIRE 16 -1 (5350 2450)(5600 2450);
WIRE 16 -1 (5600 2450)(5600 2400);
WIRE 16 -1 (5600 2500)(5350 2500);
WIRE 16 -1 (5600 2500)(5600 2450);
WIRE 16 -1 (5600 2550)(5350 2550);
WIRE 16 -1 (5600 2550)(5600 2500);
WIRE 16 -1 (5600 2600)(5600 2550);
WIRE 16 -1 (5350 2600)(5600 2600);
WIRE 16 -1 (5350 2650)(5600 2650);
WIRE 16 -1 (5600 2650)(5600 2600);
WIRE 16 -1 (5350 2700)(5600 2700);
WIRE 16 -1 (5600 2650)(5600 2700);
WIRE 16 -1 (5350 2750)(5600 2750);
WIRE 16 -1 (5600 2750)(5600 2700);
WIRE 16 -1 (5350 2800)(5600 2800);
WIRE 16 -1 (5600 2800)(5600 2750);
WIRE 16 -1 (5350 2850)(5600 2850);
WIRE 16 -1 (5600 2850)(5600 2800);
WIRE 16 -1 (5350 2900)(5600 2900);
WIRE 16 -1 (5600 2900)(5600 2850);
WIRE 16 -1 (5350 2950)(5600 2950);
WIRE 16 -1 (5600 2950)(5600 2900);
WIRE 16 -1 (5600 3000)(5350 3000);
WIRE 16 -1 (5600 3000)(5600 2950);
WIRE 16 -1 (5600 3050)(5350 3050);
WIRE 16 -1 (5600 3050)(5600 3000);
WIRE 16 -1 (5600 3100)(5600 3050);
WIRE 16 -1 (5350 3100)(5600 3100);
WIRE 16 -1 (5350 3150)(5600 3150);
WIRE 16 -1 (5600 3150)(5600 3100);
WIRE 16 -1 (5350 3200)(5600 3200);
WIRE 16 -1 (5600 3150)(5600 3200);
WIRE 16 -1 (5350 3250)(5600 3250);
WIRE 16 -1 (5600 3250)(5600 3200);
WIRE 16 -1 (5350 3300)(5600 3300);
WIRE 16 -1 (5600 3300)(5600 3250);
WIRE 16 -1 (5350 3350)(5600 3350);
WIRE 16 -1 (5600 3350)(5600 3300);
WIRE 16 -1 (5350 3400)(5600 3400);
WIRE 16 -1 (5600 3400)(5600 3350);
WIRE 16 -1 (5350 3450)(5600 3450);
WIRE 16 -1 (5600 3450)(5600 3400);
WIRE 16 -1 (5600 3500)(5350 3500);
WIRE 16 -1 (5600 3500)(5600 3450);
WIRE 16 -1 (5600 3550)(5350 3550);
WIRE 16 -1 (5600 3550)(5600 3500);
WIRE 16 -1 (5600 3600)(5600 3550);
WIRE 16 -1 (5350 3600)(5600 3600);
WIRE 16 -1 (5350 3650)(5600 3650);
WIRE 16 -1 (5600 3650)(5600 3600);
WIRE 16 -1 (5350 3700)(5600 3700);
WIRE 16 -1 (5600 3650)(5600 3700);
WIRE 16 -1 (5350 3750)(5600 3750);
WIRE 16 -1 (5600 3750)(5600 3700);
WIRE 16 -1 (5350 3800)(5600 3800);
WIRE 16 -1 (5600 3800)(5600 3750);
WIRE 16 -1 (5350 3850)(5600 3850);
WIRE 16 -1 (5600 3850)(5600 3800);
WIRE 16 -1 (5350 3900)(5600 3900);
WIRE 16 -1 (5600 3900)(5600 3850);
WIRE 16 -1 (5350 3950)(5600 3950);
WIRE 16 -1 (5600 3950)(5600 3900);
WIRE 16 -1 (5350 4000)(5600 4000);
WIRE 16 -1 (5600 4000)(5600 3950);
WIRE 16 -1 (5350 4050)(5600 4050);
WIRE 16 -1 (5600 4050)(5600 4000);
WIRE 16 -1 (5600 4100)(5600 4050);
WIRE 16 -1 (5350 4100)(5600 4100);
WIRE 16 -1 (5350 4150)(5600 4150);
WIRE 16 -1 (5600 4150)(5600 4100);
WIRE 16 -1 (5350 4200)(5600 4200);
WIRE 16 -1 (5600 4200)(5600 4150);
WIRE 16 -1 (5350 4250)(5600 4250);
WIRE 16 -1 (5600 4250)(5600 4200);
WIRE 16 -1 (5350 4300)(5600 4300);
WIRE 16 -1 (5600 4300)(5600 4250);
WIRE 16 -1 (5350 4350)(5600 4350);
WIRE 16 -1 (5600 4350)(5600 4300);
WIRE 16 -1 (5600 4400)(5600 4350);
WIRE 16 -1 (5350 4400)(5600 4400);
WIRE 16 -1 (-1950 450)(-3050 450);
FORCEPROP 2 LAST SIG_NAME PD_CHB_CPU0_DIMM2_SAA
J 0
(-2962 459);
DISPLAY 0.680851 (-2962 459);
PAINT WHITE (-2962 459);
WIRE 16 -1 (-1950 350)(-1950 450);
WIRE 16 -1 (2200 750)(2200 625);
WIRE 16 -1 (2825 750)(2200 750);
WIRE 16 -1 (2825 625)(2825 750);
DOT 1 (2200 750);
DOT 1 (2825 275);
DOT 1 (3900 1150);
DOT 1 (3900 1200);
DOT 1 (3900 1250);
DOT 1 (3900 1400);
DOT 1 (3900 1300);
DOT 1 (3900 1350);
DOT 1 (3900 1450);
DOT 1 (3900 1500);
DOT 1 (3900 1550);
DOT 1 (3900 1600);
DOT 1 (3900 1650);
DOT 1 (3900 1700);
DOT 1 (3900 1750);
DOT 1 (3900 1800);
DOT 1 (3900 1900);
DOT 1 (3900 1850);
DOT 1 (3900 1950);
DOT 1 (3900 2000);
DOT 1 (3900 2050);
DOT 1 (3900 2150);
DOT 1 (3900 2100);
DOT 1 (3900 2250);
DOT 1 (3900 2200);
DOT 1 (3900 2350);
DOT 1 (3900 2400);
DOT 1 (3900 2550);
DOT 1 (3900 2450);
DOT 1 (3900 2500);
DOT 1 (3900 2600);
DOT 1 (3900 2650);
DOT 1 (3900 2700);
DOT 1 (3900 2800);
DOT 1 (3900 2750);
DOT 1 (3900 2850);
DOT 1 (3900 2900);
DOT 1 (3900 2950);
DOT 1 (3900 3050);
DOT 1 (3900 3000);
DOT 1 (3900 3150);
DOT 1 (3900 3100);
DOT 1 (3900 3250);
DOT 1 (3900 3300);
DOT 1 (3900 3450);
DOT 1 (3900 3400);
DOT 1 (3900 3350);
DOT 1 (3900 3500);
DOT 1 (3900 3550);
DOT 1 (3900 3700);
DOT 1 (3900 3600);
DOT 1 (3900 3650);
DOT 1 (3900 3750);
DOT 1 (3900 3800);
DOT 1 (3900 3850);
DOT 1 (3900 3950);
DOT 1 (3900 3900);
DOT 1 (3900 4000);
DOT 1 (3900 4050);
DOT 1 (3900 4100);
DOT 1 (3900 4200);
DOT 1 (3900 4150);
DOT 1 (5600 1250);
DOT 1 (5600 1300);
DOT 1 (5600 1350);
DOT 1 (5600 1400);
DOT 1 (5600 1450);
DOT 1 (5600 1500);
DOT 1 (5600 1600);
DOT 1 (5600 1550);
DOT 1 (5600 1650);
DOT 1 (5600 1700);
DOT 1 (5600 1750);
DOT 1 (5600 1800);
DOT 1 (5600 1850);
DOT 1 (5600 1900);
DOT 1 (5600 1950);
DOT 1 (5600 2000);
DOT 1 (5600 2050);
DOT 1 (5600 2100);
DOT 1 (5600 2150);
DOT 1 (5600 2200);
DOT 1 (5600 2250);
DOT 1 (5600 2300);
DOT 1 (5600 2350);
DOT 1 (5600 2400);
DOT 1 (5600 2450);
DOT 1 (5600 2500);
DOT 1 (5600 2550);
DOT 1 (5600 2650);
DOT 1 (5600 2600);
DOT 1 (5600 2700);
DOT 1 (5600 2750);
DOT 1 (5600 2800);
DOT 1 (5600 2850);
DOT 1 (5600 2900);
DOT 1 (5600 2950);
DOT 1 (5600 3000);
DOT 1 (5600 3050);
DOT 1 (5600 3100);
DOT 1 (5600 3150);
DOT 1 (5600 3200);
DOT 1 (5600 3250);
DOT 1 (5600 3300);
DOT 1 (5600 3350);
DOT 1 (5600 3400);
DOT 1 (5600 3450);
DOT 1 (5600 3500);
DOT 1 (5600 3550);
DOT 1 (5600 3600);
DOT 1 (5600 3650);
DOT 1 (5600 3700);
DOT 1 (5600 3750);
DOT 1 (5600 3800);
DOT 1 (5600 3850);
DOT 1 (5600 3900);
DOT 1 (5600 3950);
DOT 1 (5600 4000);
DOT 1 (5600 4050);
DOT 1 (5600 4100);
DOT 1 (5600 4150);
DOT 1 (5600 4200);
DOT 1 (5600 4250);
DOT 1 (5600 4300);
DOT 1 (5600 4350);
DOT 1 (5600 1150);
DOT 1 (5600 1100);
DOT 1 (5600 1050);
DOT 1 (3900 3200);
DOT 1 (3900 2300);
DOT 1 (3900 4400);
DOT 1 (3900 4350);
FORCENOTE
20210728 MODIFY FOR GT
(-3475 5025) 0;
DISPLAY LEFT (-3475 5025);
DISPLAY 2.510638 (-3475 5025);
PAINT PINK (-3475 5025);
QUIT
